FILE_TYPE = MACRO_DRAWING;
SET COLOR_WIRE YELLOW;
SET COLOR_PROP ORANGE;
SET COLOR_DOT WHITE;
SET COLOR_ARC YELLOW;
SET COLOR_BODY GREEN;
SET COLOR_NOTE PURPLE;
SET PROP_DISPLAY VALUE;
SET PAGE_NUMBER P212;
FORCEADD OFFPAGE..1
(-4200 3350);
FORCEPROP 2 LAST $XR1 252 
J 0
(-4602 3350);
DISPLAY 0.638298 (-4602 3350);
PAINT MONO (-4602 3350);
FORCEPROP 2 LAST $XR0 182 
J 0
(-4482 3350);
DISPLAY 0.638298 (-4482 3350);
PAINT MONO (-4482 3350);
FORCEPROP 2 LAST PATH I1
J 0
(-4150 3425);
DISPLAY 1.021277 (-4150 3425);
DISPLAY INVISIBLE (-4150 3425);
FORCEPROP 1 LAST OFFPAGE TRUE
J 0
(-3875 3225);
DISPLAY 0.872340 (-3875 3225);
DISPLAY INVISIBLE (-3875 3225);
FORCEPROP 1 LAST COMMENT_BODY TRUE
J 0
(-4075 3250);
DISPLAY 1.170213 (-4075 3250);
PAINT GREEN (-4075 3250);
DISPLAY INVISIBLE (-4075 3250);
FORCEPROP 2 LAST CDS_LIB standard
J 0
(-4200 3350);
PAINT MONO (-4200 3350);
DISPLAY INVISIBLE (-4200 3350);
FORCEADD Q_RES..1
(-2800 2500);
FORCEPROP 1 LAST PART_NUMBER CS03322FB03
J 0
(-2900 2575);
DISPLAY 0.510638 (-2900 2575);
DISPLAY INVISIBLE (-2900 2575);
FORCEPROP 1 LAST MATERIAL CHIP
J 0
(-2525 2500);
DISPLAY 0.510638 (-2525 2500);
FORCEPROP 1 LAST WATTAGE 1/16W
J 2
(-2625 2625);
DISPLAY 0.510638 (-2625 2625);
FORCEPROP 1 LAST PACK_TYPE 0402LF
J 0
(-2900 2625);
DISPLAY 0.510638 (-2900 2625);
FORCEPROP 1 LAST TOLERANCE 1%
J 0
(-2600 2500);
DISPLAY 0.510638 (-2600 2500);
FORCEPROP 1 LAST VALUE 33.2
J 2
(-2650 2500);
DISPLAY 0.510638 (-2650 2500);
FORCEPROP 1 LAST $LOCATION R1206
J 0
(-3025 2500);
DISPLAY 0.638298 (-3025 2500);
FORCEPROP 1 LASTPIN (-2900 2500) $PN 1
J 0
(-2888 2512);
DISPLAY 0.787234 (-2888 2512);
FORCEPROP 1 LASTPIN (-2700 2500) $PN 2
J 0
(-2738 2512);
DISPLAY 0.787234 (-2738 2512);
FORCEPROP 1 LAST PATH I10
J 0
(-2850 2650);
DISPLAY 0.978723 (-2850 2650);
PAINT WHITE (-2850 2650);
DISPLAY INVISIBLE (-2850 2650);
FORCEPROP 2 LAST CDS_LIB pure_quanta
J 0
(-2800 2500);
PAINT MONO (-2800 2500);
DISPLAY INVISIBLE (-2800 2500);
FORCEPROP 2 LAST CDS_LOCATION R1206
J 0
(-2850 2700);
DISPLAY 1.021277 (-2850 2700);
DISPLAY INVISIBLE (-2850 2700);
FORCEPROP 2 LAST $SEC 1
J 0
(-2850 2700);
DISPLAY 0.680851 (-2850 2700);
PAINT MONO (-2850 2700);
DISPLAY INVISIBLE (-2850 2700);
FORCEPROP 2 LAST CDS_SEC 1
J 0
(-2850 2700);
DISPLAY 1.021277 (-2850 2700);
DISPLAY INVISIBLE (-2850 2700);
FORCEADD OFFPAGE..2
(3475 2875);
FORCEPROP 2 LAST $XR0 158 
J 0
(3664 2875);
DISPLAY 0.638298 (3664 2875);
PAINT MONO (3664 2875);
FORCEPROP 2 LAST PATH I100
J 0
(3675 2925);
DISPLAY 1.021277 (3675 2925);
DISPLAY INVISIBLE (3675 2925);
FORCEPROP 1 LAST OFFPAGE TRUE
J 0
(3800 2750);
DISPLAY 0.872340 (3800 2750);
PAINT GREEN (3800 2750);
DISPLAY INVISIBLE (3800 2750);
FORCEPROP 1 LAST COMMENT_BODY TRUE
J 0
(3430 2780);
DISPLAY 0.872340 (3430 2780);
PAINT GREEN (3430 2780);
DISPLAY INVISIBLE (3430 2780);
FORCEPROP 2 LAST CDS_LIB standard
J 0
(3475 2875);
PAINT MONO (3475 2875);
DISPLAY INVISIBLE (3475 2875);
FORCEADD Q_RES..1
(1900 2875);
FORCEPROP 1 LAST PART_NUMBER CS03322FB03
J 0
(1800 2950);
DISPLAY 0.510638 (1800 2950);
DISPLAY INVISIBLE (1800 2950);
FORCEPROP 1 LAST WATTAGE 1/16W
J 2
(2075 3000);
DISPLAY 0.510638 (2075 3000);
FORCEPROP 1 LAST VALUE 33.2
J 2
(2100 2875);
DISPLAY 0.510638 (2100 2875);
FORCEPROP 1 LAST TOLERANCE 1%
J 0
(2125 2875);
DISPLAY 0.510638 (2125 2875);
FORCEPROP 1 LAST PACK_TYPE 0402LF
J 0
(1800 3000);
DISPLAY 0.510638 (1800 3000);
FORCEPROP 1 LAST MATERIAL CHIP
J 0
(2200 2875);
DISPLAY 0.510638 (2200 2875);
FORCEPROP 1 LAST $LOCATION R1514
J 0
(1650 2875);
DISPLAY 0.510638 (1650 2875);
FORCEPROP 1 LASTPIN (1800 2875) $PN 1
J 0
(1812 2887);
DISPLAY 0.787234 (1812 2887);
FORCEPROP 1 LASTPIN (2000 2875) $PN 2
J 0
(1962 2887);
DISPLAY 0.787234 (1962 2887);
FORCEPROP 1 LAST PATH I105
J 0
(1850 3025);
DISPLAY 0.978723 (1850 3025);
PAINT WHITE (1850 3025);
DISPLAY INVISIBLE (1850 3025);
FORCEPROP 2 LAST CDS_LIB pure_quanta
J 0
(1900 2875);
PAINT MONO (1900 2875);
DISPLAY INVISIBLE (1900 2875);
FORCEPROP 2 LAST CDS_LOCATION R1514
J 0
(1850 3075);
DISPLAY 1.021277 (1850 3075);
DISPLAY INVISIBLE (1850 3075);
FORCEPROP 2 LAST $SEC 1
J 0
(1850 3075);
DISPLAY 0.680851 (1850 3075);
PAINT MONO (1850 3075);
DISPLAY INVISIBLE (1850 3075);
FORCEPROP 2 LAST CDS_SEC 1
J 0
(1850 3075);
DISPLAY 1.021277 (1850 3075);
DISPLAY INVISIBLE (1850 3075);
FORCEADD OFFPAGE..2
(3475 925);
FORCEPROP 2 LAST $XR0 164 
J 0
(3664 925);
DISPLAY 0.638298 (3664 925);
PAINT MONO (3664 925);
FORCEPROP 2 LAST PATH I111
J 0
(3675 975);
DISPLAY 1.021277 (3675 975);
DISPLAY INVISIBLE (3675 975);
FORCEPROP 2 LAST CDS_LIB standard
J 0
(3475 925);
PAINT MONO (3475 925);
DISPLAY INVISIBLE (3475 925);
FORCEPROP 1 LAST COMMENT_BODY TRUE
J 0
(3430 830);
DISPLAY 0.872340 (3430 830);
PAINT GREEN (3430 830);
DISPLAY INVISIBLE (3430 830);
FORCEPROP 1 LAST OFFPAGE TRUE
J 0
(3800 800);
DISPLAY 0.872340 (3800 800);
PAINT GREEN (3800 800);
DISPLAY INVISIBLE (3800 800);
FORCEADD Q_RES..1
(1900 925);
FORCEPROP 1 LAST PART_NUMBER CS03322FB03
J 0
(1800 1000);
DISPLAY 0.510638 (1800 1000);
DISPLAY INVISIBLE (1800 1000);
FORCEPROP 1 LAST WATTAGE 1/16W
J 2
(2075 1050);
DISPLAY 0.510638 (2075 1050);
FORCEPROP 1 LAST MATERIAL CHIP
J 0
(1800 1050);
DISPLAY 0.510638 (1800 1050);
FORCEPROP 1 LAST TOLERANCE 1%
J 0
(2125 925);
DISPLAY 0.510638 (2125 925);
FORCEPROP 1 LAST VALUE 33.2
J 2
(2100 925);
DISPLAY 0.510638 (2100 925);
FORCEPROP 1 LAST PACK_TYPE 0402LF
J 0
(2200 925);
DISPLAY 0.510638 (2200 925);
FORCEPROP 1 LAST $LOCATION R1520
J 0
(1650 925);
DISPLAY 0.510638 (1650 925);
FORCEPROP 1 LASTPIN (1800 925) $PN 1
J 0
(1812 937);
DISPLAY 0.787234 (1812 937);
FORCEPROP 1 LASTPIN (2000 925) $PN 2
J 0
(1962 937);
DISPLAY 0.787234 (1962 937);
FORCEPROP 1 LAST PATH I113
J 0
(1850 1075);
DISPLAY 0.978723 (1850 1075);
PAINT WHITE (1850 1075);
DISPLAY INVISIBLE (1850 1075);
FORCEPROP 2 LAST CDS_LIB pure_quanta
J 0
(1900 925);
PAINT MONO (1900 925);
DISPLAY INVISIBLE (1900 925);
FORCEPROP 2 LAST CDS_LOCATION R1520
J 0
(1850 1125);
DISPLAY 1.021277 (1850 1125);
DISPLAY INVISIBLE (1850 1125);
FORCEPROP 2 LAST $SEC 1
J 0
(1850 1125);
DISPLAY 0.680851 (1850 1125);
PAINT MONO (1850 1125);
DISPLAY INVISIBLE (1850 1125);
FORCEPROP 2 LAST CDS_SEC 1
J 0
(1850 1125);
DISPLAY 1.021277 (1850 1125);
DISPLAY INVISIBLE (1850 1125);
FORCEADD OFFPAGE..2
(3475 300);
FORCEPROP 2 LAST $XR0 149 
J 0
(3664 300);
DISPLAY 0.638298 (3664 300);
PAINT MONO (3664 300);
FORCEPROP 2 LAST PATH I126
J 0
(3675 350);
DISPLAY 1.021277 (3675 350);
DISPLAY INVISIBLE (3675 350);
FORCEPROP 1 LAST OFFPAGE TRUE
J 0
(3800 175);
DISPLAY 0.872340 (3800 175);
PAINT GREEN (3800 175);
DISPLAY INVISIBLE (3800 175);
FORCEPROP 1 LAST COMMENT_BODY TRUE
J 0
(3430 205);
DISPLAY 0.872340 (3430 205);
PAINT GREEN (3430 205);
DISPLAY INVISIBLE (3430 205);
FORCEPROP 2 LAST CDS_LIB standard
J 0
(3475 300);
DISPLAY INVISIBLE (3475 300);
FORCEADD Q_RES..1
(1900 300);
FORCEPROP 1 LAST PART_NUMBER CS03322FB03
J 0
(1800 375);
DISPLAY 0.510638 (1800 375);
DISPLAY INVISIBLE (1800 375);
FORCEPROP 1 LAST VALUE 33.2
J 2
(2100 300);
DISPLAY 0.510638 (2100 300);
FORCEPROP 1 LAST TOLERANCE 1%
J 0
(2125 300);
DISPLAY 0.510638 (2125 300);
FORCEPROP 1 LAST MATERIAL CHIP
J 0
(2200 300);
DISPLAY 0.510638 (2200 300);
FORCEPROP 1 LAST WATTAGE 1/16W
J 2
(2075 425);
DISPLAY 0.510638 (2075 425);
FORCEPROP 1 LAST PACK_TYPE 0402LF
J 0
(1800 425);
DISPLAY 0.510638 (1800 425);
FORCEPROP 1 LAST $LOCATION R2738
J 0
(1650 300);
DISPLAY 0.510638 (1650 300);
FORCEPROP 1 LASTPIN (1800 300) $PN 1
J 0
(1812 312);
DISPLAY 0.787234 (1812 312);
FORCEPROP 1 LASTPIN (2000 300) $PN 2
J 0
(1962 312);
DISPLAY 0.787234 (1962 312);
FORCEPROP 1 LAST PATH I127
J 0
(1850 450);
DISPLAY 0.978723 (1850 450);
PAINT WHITE (1850 450);
DISPLAY INVISIBLE (1850 450);
FORCEPROP 2 LAST CDS_LIB pure_quanta
J 0
(1900 300);
PAINT MONO (1900 300);
DISPLAY INVISIBLE (1900 300);
FORCEPROP 2 LAST CDS_LOCATION R2738
J 0
(1850 500);
DISPLAY 1.021277 (1850 500);
DISPLAY INVISIBLE (1850 500);
FORCEPROP 2 LAST $SEC 1
J 0
(1850 500);
DISPLAY 0.680851 (1850 500);
PAINT MONO (1850 500);
DISPLAY INVISIBLE (1850 500);
FORCEPROP 2 LAST CDS_SEC 1
J 0
(1850 500);
DISPLAY 1.021277 (1850 500);
DISPLAY INVISIBLE (1850 500);
FORCEADD OFFPAGE..2
(-1225 2075);
FORCEPROP 2 LAST $XR0 228 
J 0
(-1036 2075);
DISPLAY 0.638298 (-1036 2075);
PAINT MONO (-1036 2075);
FORCEPROP 2 LAST PATH I128
J 0
(-1025 2125);
DISPLAY 1.021277 (-1025 2125);
DISPLAY INVISIBLE (-1025 2125);
FORCEPROP 1 LAST OFFPAGE TRUE
J 0
(-900 1950);
DISPLAY 0.872340 (-900 1950);
PAINT GREEN (-900 1950);
DISPLAY INVISIBLE (-900 1950);
FORCEPROP 1 LAST COMMENT_BODY TRUE
J 0
(-1270 1980);
DISPLAY 0.872340 (-1270 1980);
PAINT GREEN (-1270 1980);
DISPLAY INVISIBLE (-1270 1980);
FORCEPROP 2 LAST CDS_LIB standard
J 0
(-1225 2075);
PAINT MONO (-1225 2075);
DISPLAY INVISIBLE (-1225 2075);
FORCEADD Q_RES..1
(-2800 2075);
FORCEPROP 1 LAST PART_NUMBER CS03322FB03
J 0
(-2900 2150);
DISPLAY 0.510638 (-2900 2150);
DISPLAY INVISIBLE (-2900 2150);
FORCEPROP 1 LAST TOLERANCE 1%
J 0
(-2575 2075);
DISPLAY 0.510638 (-2575 2075);
FORCEPROP 1 LAST VALUE 33.2
J 2
(-2600 2075);
DISPLAY 0.510638 (-2600 2075);
FORCEPROP 1 LAST MATERIAL CHIP
J 0
(-2900 2200);
DISPLAY 0.510638 (-2900 2200);
FORCEPROP 1 LAST PACK_TYPE 0402LF
J 0
(-2500 2075);
DISPLAY 0.510638 (-2500 2075);
FORCEPROP 1 LAST WATTAGE 1/16W
J 2
(-2625 2200);
DISPLAY 0.510638 (-2625 2200);
FORCEPROP 1 LAST $LOCATION R3050
J 0
(-3050 2075);
DISPLAY 0.638298 (-3050 2075);
FORCEPROP 1 LASTPIN (-2900 2075) $PN 1
J 0
(-2888 2087);
DISPLAY 0.787234 (-2888 2087);
FORCEPROP 1 LASTPIN (-2700 2075) $PN 2
J 0
(-2738 2087);
DISPLAY 0.787234 (-2738 2087);
FORCEPROP 1 LAST PATH I129
J 0
(-2850 2225);
DISPLAY 0.978723 (-2850 2225);
PAINT WHITE (-2850 2225);
DISPLAY INVISIBLE (-2850 2225);
FORCEPROP 2 LAST CDS_LIB pure_quanta
J 0
(-2800 2075);
PAINT MONO (-2800 2075);
DISPLAY INVISIBLE (-2800 2075);
FORCEPROP 2 LAST CDS_LOCATION R3050
J 0
(-2850 2275);
DISPLAY 1.021277 (-2850 2275);
DISPLAY INVISIBLE (-2850 2275);
FORCEPROP 2 LAST $SEC 1
J 0
(-2850 2275);
DISPLAY 0.680851 (-2850 2275);
PAINT MONO (-2850 2275);
DISPLAY INVISIBLE (-2850 2275);
FORCEPROP 2 LAST CDS_SEC 1
J 0
(-2850 2275);
DISPLAY 1.021277 (-2850 2275);
DISPLAY INVISIBLE (-2850 2275);
FORCEADD OFFPAGE..1
(-4200 2275);
FORCEPROP 2 LAST $XR2 252 
J 0
(-4722 2275);
DISPLAY 0.638298 (-4722 2275);
PAINT MONO (-4722 2275);
FORCEPROP 2 LAST $XR1 219 
J 0
(-4602 2275);
DISPLAY 0.638298 (-4602 2275);
PAINT MONO (-4602 2275);
FORCEPROP 2 LAST $XR0 215 
J 0
(-4482 2275);
DISPLAY 0.638298 (-4482 2275);
PAINT MONO (-4482 2275);
FORCEPROP 2 LAST CDS_LIB standard
J 0
(-4200 2275);
PAINT MONO (-4200 2275);
DISPLAY INVISIBLE (-4200 2275);
FORCEPROP 2 LAST PATH I13
J 0
(-4150 2350);
DISPLAY 1.021277 (-4150 2350);
DISPLAY INVISIBLE (-4150 2350);
FORCEPROP 1 LAST COMMENT_BODY TRUE
J 0
(-4075 2175);
DISPLAY 1.170213 (-4075 2175);
PAINT GREEN (-4075 2175);
DISPLAY INVISIBLE (-4075 2175);
FORCEPROP 1 LAST OFFPAGE TRUE
J 0
(-3875 2150);
DISPLAY 0.872340 (-3875 2150);
DISPLAY INVISIBLE (-3875 2150);
FORCEADD Q_RES..1
(1925 3775);
FORCEPROP 1 LAST PART_NUMBER CS00002JB13
J 0
(1825 3850);
DISPLAY 0.404255 (1825 3850);
DISPLAY INVISIBLE (1825 3850);
FORCEPROP 1 LAST VALUE 0
J 2
(2075 3775);
DISPLAY 0.510638 (2075 3775);
FORCEPROP 1 LAST WATTAGE 1/16W
J 2
(2050 3875);
DISPLAY 0.404255 (2050 3875);
FORCEPROP 1 LAST PACK_TYPE 0402LF
J 0
(1825 3875);
DISPLAY 0.404255 (1825 3875);
FORCEPROP 1 LAST TOLERANCE 5%
J 0
(2125 3775);
DISPLAY 0.510638 (2125 3775);
FORCEPROP 1 LAST MATERIAL CHIP
J 0
(2200 3775);
DISPLAY 0.510638 (2200 3775);
FORCEPROP 1 LAST LOCATION R1318
J 0
(1675 3775);
DISPLAY 0.638298 (1675 3775);
FORCEPROP 1 LASTPIN (1825 3775) $PN 1
J 0
(1837 3787);
DISPLAY 0.787234 (1837 3787);
PAINT MONO (1837 3787);
FORCEPROP 1 LASTPIN (2025 3775) $PN 2
J 0
(1987 3787);
DISPLAY 0.787234 (1987 3787);
PAINT MONO (1987 3787);
FORCEPROP 1 LAST PATH I130
J 0
(1875 3925);
DISPLAY 0.978723 (1875 3925);
PAINT WHITE (1875 3925);
DISPLAY INVISIBLE (1875 3925);
FORCEPROP 2 LAST CDS_LIB pure_quanta
J 0
(1925 3775);
DISPLAY INVISIBLE (1925 3775);
FORCEPROP 0 LAST $SEC 1
J 0
(2050 3900);
DISPLAY 0.680851 (2050 3900);
PAINT MONO (2050 3900);
DISPLAY INVISIBLE (2050 3900);
FORCEPROP 0 LAST CDS_SEC 1
J 0
(2050 3900);
DISPLAY 1.021277 (2050 3900);
DISPLAY INVISIBLE (2050 3900);
FORCEADD OFFPAGE..1
(325 300);
FORCEPROP 2 LAST $XR1 219 
J 0
(-77 300);
DISPLAY 0.638298 (-77 300);
PAINT MONO (-77 300);
FORCEPROP 2 LAST $XR0 214 
J 0
(43 300);
DISPLAY 0.638298 (43 300);
PAINT MONO (43 300);
FORCEPROP 1 LAST OFFPAGE TRUE
J 0
(650 175);
DISPLAY 0.872340 (650 175);
DISPLAY INVISIBLE (650 175);
FORCEPROP 1 LAST COMMENT_BODY TRUE
J 0
(450 200);
DISPLAY 1.170213 (450 200);
PAINT GREEN (450 200);
DISPLAY INVISIBLE (450 200);
FORCEPROP 2 LAST PATH I131
J 0
(375 375);
DISPLAY 1.021277 (375 375);
DISPLAY INVISIBLE (375 375);
FORCEPROP 2 LAST CDS_LIB standard
J 0
(325 300);
DISPLAY INVISIBLE (325 300);
FORCEADD OFFPAGE..2
(-1400 2275);
FORCEPROP 2 LAST $XR2 182 
J 0
(-971 2275);
DISPLAY 0.638298 (-971 2275);
PAINT MONO (-971 2275);
FORCEPROP 2 LAST $XR1 131 
J 0
(-1091 2275);
DISPLAY 0.638298 (-1091 2275);
PAINT MONO (-1091 2275);
FORCEPROP 2 LAST $XR0 244 
J 0
(-1211 2275);
DISPLAY 0.638298 (-1211 2275);
PAINT MONO (-1211 2275);
FORCEPROP 2 LAST CDS_LIB standard
J 0
(-1400 2275);
PAINT MONO (-1400 2275);
DISPLAY INVISIBLE (-1400 2275);
FORCEPROP 2 LAST PATH I14
J 0
(-1225 2350);
DISPLAY 1.021277 (-1225 2350);
DISPLAY INVISIBLE (-1225 2350);
FORCEPROP 1 LAST OFFPAGE TRUE
J 0
(-1075 2150);
DISPLAY 0.872340 (-1075 2150);
PAINT GREEN (-1075 2150);
DISPLAY INVISIBLE (-1075 2150);
FORCEPROP 1 LAST COMMENT_BODY TRUE
J 0
(-1445 2180);
DISPLAY 0.872340 (-1445 2180);
PAINT GREEN (-1445 2180);
DISPLAY INVISIBLE (-1445 2180);
FORCEADD Q_RES..1
(-2800 2275);
FORCEPROP 1 LAST PART_NUMBER CS03322FB03
J 0
(-2900 2350);
DISPLAY 0.510638 (-2900 2350);
DISPLAY INVISIBLE (-2900 2350);
FORCEPROP 1 LAST TOLERANCE 1%
J 0
(-2600 2275);
DISPLAY 0.510638 (-2600 2275);
FORCEPROP 1 LAST VALUE 33.2
J 2
(-2650 2275);
DISPLAY 0.510638 (-2650 2275);
FORCEPROP 1 LAST PACK_TYPE 0402LF
J 0
(-2525 2275);
DISPLAY 0.510638 (-2525 2275);
FORCEPROP 1 LAST MATERIAL CHIP
J 0
(-2900 2400);
DISPLAY 0.510638 (-2900 2400);
FORCEPROP 1 LAST WATTAGE 1/16W
J 2
(-2650 2400);
DISPLAY 0.510638 (-2650 2400);
FORCEPROP 1 LAST $LOCATION R1207
J 0
(-3025 2275);
DISPLAY 0.638298 (-3025 2275);
FORCEPROP 1 LASTPIN (-2900 2275) $PN 1
J 0
(-2888 2287);
DISPLAY 0.787234 (-2888 2287);
FORCEPROP 1 LASTPIN (-2700 2275) $PN 2
J 0
(-2738 2287);
DISPLAY 0.787234 (-2738 2287);
FORCEPROP 1 LAST PATH I15
J 0
(-2850 2425);
DISPLAY 0.978723 (-2850 2425);
PAINT WHITE (-2850 2425);
DISPLAY INVISIBLE (-2850 2425);
FORCEPROP 2 LAST CDS_LIB pure_quanta
J 0
(-2800 2275);
PAINT MONO (-2800 2275);
DISPLAY INVISIBLE (-2800 2275);
FORCEPROP 2 LAST CDS_LOCATION R1207
J 0
(-2850 2475);
DISPLAY 1.021277 (-2850 2475);
DISPLAY INVISIBLE (-2850 2475);
FORCEPROP 2 LAST $SEC 1
J 0
(-2850 2475);
DISPLAY 0.680851 (-2850 2475);
PAINT MONO (-2850 2475);
DISPLAY INVISIBLE (-2850 2475);
FORCEPROP 2 LAST CDS_SEC 1
J 0
(-2850 2475);
DISPLAY 1.021277 (-2850 2475);
DISPLAY INVISIBLE (-2850 2475);
FORCEADD OFFPAGE..1
(-4200 1575);
FORCEPROP 2 LAST $XR0 215 
J 0
(-4482 1575);
DISPLAY 0.638298 (-4482 1575);
PAINT MONO (-4482 1575);
FORCEPROP 2 LAST CDS_LIB standard
J 0
(-4200 1575);
PAINT MONO (-4200 1575);
DISPLAY INVISIBLE (-4200 1575);
FORCEPROP 1 LAST OFFPAGE TRUE
J 0
(-3875 1450);
DISPLAY 0.872340 (-3875 1450);
PAINT GREEN (-3875 1450);
DISPLAY INVISIBLE (-3875 1450);
FORCEPROP 1 LAST COMMENT_BODY TRUE
J 0
(-4075 1475);
DISPLAY 0.872340 (-4075 1475);
PAINT GREEN (-4075 1475);
DISPLAY INVISIBLE (-4075 1475);
FORCEPROP 2 LAST PATH I16
J 0
(-4150 1650);
DISPLAY 1.021277 (-4150 1650);
DISPLAY INVISIBLE (-4150 1650);
FORCEADD Q_RES..1
(-2800 1575);
FORCEPROP 1 LAST PART_NUMBER CS03322FB03
J 0
(-2900 1650);
DISPLAY 0.510638 (-2900 1650);
DISPLAY INVISIBLE (-2900 1650);
FORCEPROP 1 LAST MATERIAL CHIP
J 0
(-2900 1700);
DISPLAY 0.510638 (-2900 1700);
FORCEPROP 1 LAST TOLERANCE 1%
J 0
(-2575 1575);
DISPLAY 0.510638 (-2575 1575);
FORCEPROP 1 LAST VALUE 33.2
J 2
(-2600 1575);
DISPLAY 0.510638 (-2600 1575);
FORCEPROP 1 LAST PACK_TYPE 0402LF
J 0
(-2500 1575);
DISPLAY 0.510638 (-2500 1575);
FORCEPROP 1 LAST WATTAGE 1/16W
J 2
(-2625 1700);
DISPLAY 0.510638 (-2625 1700);
FORCEPROP 1 LAST $LOCATION R110
J 0
(-3025 1575);
DISPLAY 0.638298 (-3025 1575);
FORCEPROP 1 LASTPIN (-2900 1575) $PN 1
J 0
(-2888 1587);
DISPLAY 0.787234 (-2888 1587);
FORCEPROP 1 LASTPIN (-2700 1575) $PN 2
J 0
(-2738 1587);
DISPLAY 0.787234 (-2738 1587);
FORCEPROP 1 LAST PATH I17
J 0
(-2850 1725);
DISPLAY 0.978723 (-2850 1725);
PAINT WHITE (-2850 1725);
DISPLAY INVISIBLE (-2850 1725);
FORCEPROP 2 LAST CDS_LIB pure_quanta
J 0
(-2800 1575);
PAINT MONO (-2800 1575);
DISPLAY INVISIBLE (-2800 1575);
FORCEPROP 2 LAST CDS_LOCATION R110
J 0
(-2850 1775);
DISPLAY 1.021277 (-2850 1775);
DISPLAY INVISIBLE (-2850 1775);
FORCEPROP 2 LAST $SEC 1
J 0
(-2850 1775);
DISPLAY 0.680851 (-2850 1775);
PAINT MONO (-2850 1775);
DISPLAY INVISIBLE (-2850 1775);
FORCEPROP 2 LAST CDS_SEC 1
J 0
(-2850 1775);
DISPLAY 1.021277 (-2850 1775);
DISPLAY INVISIBLE (-2850 1775);
FORCEADD OFFPAGE..2
(-1400 1575);
FORCEPROP 2 LAST $XR3 223 
J 0
(-851 1575);
DISPLAY 0.638298 (-851 1575);
PAINT MONO (-851 1575);
FORCEPROP 2 LAST $XR2 211 
J 0
(-971 1575);
DISPLAY 0.638298 (-971 1575);
PAINT MONO (-971 1575);
FORCEPROP 2 LAST $XR1 206 
J 0
(-1091 1575);
DISPLAY 0.638298 (-1091 1575);
PAINT MONO (-1091 1575);
FORCEPROP 2 LAST $XR0 208 
J 0
(-1211 1575);
DISPLAY 0.638298 (-1211 1575);
PAINT MONO (-1211 1575);
FORCEPROP 1 LAST COMMENT_BODY TRUE
J 0
(-1445 1480);
DISPLAY 0.872340 (-1445 1480);
PAINT GREEN (-1445 1480);
DISPLAY INVISIBLE (-1445 1480);
FORCEPROP 1 LAST OFFPAGE TRUE
J 0
(-1075 1450);
DISPLAY 0.872340 (-1075 1450);
PAINT GREEN (-1075 1450);
DISPLAY INVISIBLE (-1075 1450);
FORCEPROP 2 LAST PATH I18
J 0
(-1050 1625);
DISPLAY 1.021277 (-1050 1625);
DISPLAY INVISIBLE (-1050 1625);
FORCEPROP 2 LAST CDS_LIB standard
J 0
(-1400 1575);
PAINT MONO (-1400 1575);
DISPLAY INVISIBLE (-1400 1575);
FORCEADD MOSFET_N..1
(-2800 675);
FORCEPROP 1 LAST PART_NUMBER BAM138K0000
J 0
(-2653 586);
DISPLAY 0.574468 (-2653 586);
PAINT GREEN (-2653 586);
DISPLAY INVISIBLE (-2653 586);
FORCEPROP 1 LAST VALUE BSS138K
J 0
(-2653 746);
DISPLAY 0.574468 (-2653 746);
PAINT GREEN (-2653 746);
FORCEPROP 1 LAST MATERIAL IC
J 0
(-2653 506);
DISPLAY 0.574468 (-2653 506);
PAINT GREEN (-2653 506);
FORCEPROP 1 LAST $LOCATION U70
J 0
(-2653 666);
DISPLAY 0.723404 (-2653 666);
PAINT GREEN (-2653 666);
FORCEPROP 1 LASTPIN (-2750 775) $PN D
R 1
J 0
(-2750 768);
DISPLAY 0.659574 (-2750 768);
PAINT GREEN (-2750 768);
FORCEPROP 1 LASTPIN (-2900 575) $PN G
J 2
(-2890 578);
DISPLAY 0.659574 (-2890 578);
PAINT GREEN (-2890 578);
FORCEPROP 1 LASTPIN (-2750 475) $PN S
R 1
J 2
(-2750 488);
DISPLAY 0.659574 (-2750 488);
PAINT GREEN (-2750 488);
FORCEPROP 0 LAST MANUF_PN BSS138K
J 0
(-2625 550);
DISPLAY 0.808511 (-2625 550);
DISPLAY INVISIBLE (-2625 550);
FORCEPROP 1 LAST PACK_TYPE SMLF
J 0
(-2775 425);
DISPLAY 0.723404 (-2775 425);
PAINT GREEN (-2775 425);
DISPLAY INVISIBLE (-2775 425);
FORCEPROP 1 LAST CDS_LMAN_SYM_OUTLINE -50,50,100,-150
J 0
(-2800 675);
DISPLAY 0.468085 (-2800 675);
PAINT GREEN (-2800 675);
DISPLAY INVISIBLE (-2800 675);
FORCEPROP 2 LAST CDS_LIB pure_quanta
J 0
(-2800 675);
PAINT MONO (-2800 675);
DISPLAY INVISIBLE (-2800 675);
FORCEPROP 0 LAST PATH I19
J 0
(-2650 775);
DISPLAY 1.021277 (-2650 775);
DISPLAY INVISIBLE (-2650 775);
FORCEPROP 2 LAST CDS_LOCATION U70
J 0
(-2650 825);
DISPLAY 1.021277 (-2650 825);
DISPLAY INVISIBLE (-2650 825);
FORCEPROP 2 LAST $SEC 1
J 0
(-2650 825);
DISPLAY 0.680851 (-2650 825);
PAINT MONO (-2650 825);
DISPLAY INVISIBLE (-2650 825);
FORCEPROP 2 LAST CDS_SEC 1
J 0
(-2650 825);
DISPLAY 1.021277 (-2650 825);
DISPLAY INVISIBLE (-2650 825);
FORCEADD OFFPAGE..2
(-1400 3350);
FORCEPROP 2 LAST $XR0 215 
J 0
(-1211 3350);
DISPLAY 0.638298 (-1211 3350);
PAINT MONO (-1211 3350);
FORCEPROP 2 LAST PATH I2
J 0
(-1225 3425);
DISPLAY 1.021277 (-1225 3425);
DISPLAY INVISIBLE (-1225 3425);
FORCEPROP 1 LAST OFFPAGE TRUE
J 0
(-1075 3225);
DISPLAY 0.872340 (-1075 3225);
PAINT GREEN (-1075 3225);
DISPLAY INVISIBLE (-1075 3225);
FORCEPROP 1 LAST COMMENT_BODY TRUE
J 0
(-1445 3255);
DISPLAY 0.872340 (-1445 3255);
PAINT GREEN (-1445 3255);
DISPLAY INVISIBLE (-1445 3255);
FORCEPROP 2 LAST CDS_LIB standard
J 0
(-1400 3350);
PAINT MONO (-1400 3350);
DISPLAY INVISIBLE (-1400 3350);
FORCEADD OFFPAGE..1
(-4200 575);
FORCEPROP 2 LAST $XR3 211 
J 0
(-4842 575);
DISPLAY 0.638298 (-4842 575);
PAINT MONO (-4842 575);
FORCEPROP 2 LAST $XR2 206 
J 0
(-4722 575);
DISPLAY 0.638298 (-4722 575);
PAINT MONO (-4722 575);
FORCEPROP 2 LAST $XR1 223 
J 0
(-4602 575);
DISPLAY 0.638298 (-4602 575);
PAINT MONO (-4602 575);
FORCEPROP 2 LAST $XR0 208 
J 0
(-4482 575);
DISPLAY 0.638298 (-4482 575);
PAINT MONO (-4482 575);
FORCEPROP 1 LAST COMMENT_BODY TRUE
J 0
(-4075 475);
DISPLAY 0.872340 (-4075 475);
PAINT GREEN (-4075 475);
DISPLAY INVISIBLE (-4075 475);
FORCEPROP 1 LAST OFFPAGE TRUE
J 0
(-3875 450);
DISPLAY 0.872340 (-3875 450);
PAINT GREEN (-3875 450);
DISPLAY INVISIBLE (-3875 450);
FORCEPROP 2 LAST PATH I20
J 0
(-4150 650);
DISPLAY 1.021277 (-4150 650);
DISPLAY INVISIBLE (-4150 650);
FORCEPROP 2 LAST CDS_LIB standard
J 0
(-4200 575);
PAINT MONO (-4200 575);
DISPLAY INVISIBLE (-4200 575);
FORCEADD Q_RES..2
(-2750 1075);
FORCEPROP 1 LAST PART_NUMBER CS31002FB08
J 0
(-2710 950);
DISPLAY 0.510638 (-2710 950);
DISPLAY INVISIBLE (-2710 950);
FORCEPROP 1 LAST PACK_TYPE 0402LF
J 0
(-2710 900);
DISPLAY 0.510638 (-2710 900);
FORCEPROP 1 LAST TOLERANCE 1%
J 0
(-2705 1100);
DISPLAY 0.510638 (-2705 1100);
FORCEPROP 1 LAST VALUE 10K
J 0
(-2705 1150);
DISPLAY 0.510638 (-2705 1150);
FORCEPROP 1 LAST WATTAGE 1/16W
J 0
(-2710 1050);
DISPLAY 0.510638 (-2710 1050);
FORCEPROP 1 LAST MATERIAL CHIP
J 0
(-2710 1000);
DISPLAY 0.510638 (-2710 1000);
FORCEPROP 1 LAST $LOCATION R111
J 0
(-2705 1200);
DISPLAY 0.978723 (-2705 1200);
FORCEPROP 1 LASTPIN (-2750 1175) $PN 1
J 0
(-2745 1137);
DISPLAY 0.787234 (-2745 1137);
FORCEPROP 1 LASTPIN (-2750 975) $PN 2
J 0
(-2745 985);
DISPLAY 0.787234 (-2745 985);
FORCEPROP 1 LAST PATH I24
J 0
(-2700 1250);
DISPLAY 0.978723 (-2700 1250);
PAINT WHITE (-2700 1250);
DISPLAY INVISIBLE (-2700 1250);
FORCEPROP 2 LAST CDS_LIB pure_quanta
J 0
(-2750 1075);
PAINT MONO (-2750 1075);
DISPLAY INVISIBLE (-2750 1075);
FORCEPROP 2 LAST CDS_LOCATION R111
J 0
(-2700 1300);
DISPLAY 1.021277 (-2700 1300);
DISPLAY INVISIBLE (-2700 1300);
FORCEPROP 2 LAST $SEC 1
J 0
(-2700 1300);
DISPLAY 0.680851 (-2700 1300);
PAINT MONO (-2700 1300);
DISPLAY INVISIBLE (-2700 1300);
FORCEPROP 2 LAST CDS_SEC 1
J 0
(-2700 1300);
DISPLAY 1.021277 (-2700 1300);
DISPLAY INVISIBLE (-2700 1300);
FORCEADD UNIVERSAL_POWER..1
(-2750 1275);
FORCEPROP 3 LASTPIN (-2750 1225) SIG_NAME P3V3\g
J 0
(-2740 1235);
DISPLAY 0.659574 (-2740 1235);
PAINT MONO (-2740 1235);
DISPLAY INVISIBLE (-2740 1235);
FORCEPROP 1 LAST HDL_POWER P3V3
J 1
(-2750 1325);
DISPLAY 0.872340 (-2750 1325);
PAINT GREEN (-2750 1325);
FORCEPROP 2 LAST CDS_LIB logical_power
J 0
(-2750 1275);
PAINT MONO (-2750 1275);
DISPLAY INVISIBLE (-2750 1275);
FORCEPROP 1 LAST PATH I25
J 0
(-2700 1300);
DISPLAY 0.872340 (-2700 1300);
PAINT AQUA (-2700 1300);
DISPLAY INVISIBLE (-2700 1300);
FORCEADD UNIVERSAL_GND..1
(-2750 275);
FORCEPROP 3 LASTPIN (-2750 325) SIG_NAME GND\g
J 0
(-2740 335);
DISPLAY 0.659574 (-2740 335);
PAINT MONO (-2740 335);
DISPLAY INVISIBLE (-2740 335);
FORCEPROP 1 LAST HDL_POWER GND
J 1
(-2725 200);
DISPLAY 0.872340 (-2725 200);
PAINT GREEN (-2725 200);
DISPLAY INVISIBLE (-2725 200);
FORCEPROP 1 LAST PATH I26
J 0
(-2675 275);
DISPLAY 0.872340 (-2675 275);
PAINT AQUA (-2675 275);
DISPLAY INVISIBLE (-2675 275);
FORCEPROP 2 LAST CDS_LIB logical_power
J 0
(-2750 275);
PAINT MONO (-2750 275);
DISPLAY INVISIBLE (-2750 275);
FORCEADD Q_RES..1
(-1550 825);
FORCEPROP 1 LAST PART_NUMBER CS03322FB03
J 0
(-1650 900);
DISPLAY 0.510638 (-1650 900);
DISPLAY INVISIBLE (-1650 900);
FORCEPROP 1 LAST TOLERANCE 1%
J 0
(-1325 825);
DISPLAY 0.510638 (-1325 825);
FORCEPROP 1 LAST VALUE 33.2
J 2
(-1350 825);
DISPLAY 0.510638 (-1350 825);
FORCEPROP 1 LAST PACK_TYPE 0402LF
J 0
(-1250 825);
DISPLAY 0.510638 (-1250 825);
FORCEPROP 1 LAST MATERIAL CHIP
J 0
(-1650 950);
DISPLAY 0.510638 (-1650 950);
FORCEPROP 1 LAST WATTAGE 1/16W
J 2
(-1375 950);
DISPLAY 0.510638 (-1375 950);
FORCEPROP 1 LAST $LOCATION R113
J 0
(-1775 825);
DISPLAY 0.638298 (-1775 825);
FORCEPROP 1 LASTPIN (-1650 825) $PN 1
J 0
(-1638 837);
DISPLAY 0.787234 (-1638 837);
FORCEPROP 1 LASTPIN (-1450 825) $PN 2
J 0
(-1488 837);
DISPLAY 0.787234 (-1488 837);
FORCEPROP 2 LAST CDS_LIB pure_quanta
J 0
(-1550 825);
PAINT MONO (-1550 825);
DISPLAY INVISIBLE (-1550 825);
FORCEPROP 1 LAST PATH I27
J 0
(-1600 975);
DISPLAY 0.978723 (-1600 975);
PAINT WHITE (-1600 975);
DISPLAY INVISIBLE (-1600 975);
FORCEPROP 2 LAST CDS_LOCATION R113
J 0
(-1600 1025);
DISPLAY 1.021277 (-1600 1025);
DISPLAY INVISIBLE (-1600 1025);
FORCEPROP 2 LAST $SEC 1
J 0
(-1600 1025);
DISPLAY 0.680851 (-1600 1025);
PAINT MONO (-1600 1025);
DISPLAY INVISIBLE (-1600 1025);
FORCEPROP 2 LAST CDS_SEC 1
J 0
(-1600 1025);
DISPLAY 1.021277 (-1600 1025);
DISPLAY INVISIBLE (-1600 1025);
FORCEADD OFFPAGE..2
(-200 825);
FORCEPROP 2 LAST $XR0 206 
J 0
(-11 825);
DISPLAY 0.638298 (-11 825);
PAINT MONO (-11 825);
FORCEPROP 1 LAST COMMENT_BODY TRUE
J 0
(-245 730);
DISPLAY 0.872340 (-245 730);
PAINT GREEN (-245 730);
DISPLAY INVISIBLE (-245 730);
FORCEPROP 1 LAST OFFPAGE TRUE
J 0
(125 700);
DISPLAY 0.872340 (125 700);
PAINT GREEN (125 700);
DISPLAY INVISIBLE (125 700);
FORCEPROP 2 LAST PATH I28
J 0
(150 875);
DISPLAY 1.021277 (150 875);
DISPLAY INVISIBLE (150 875);
FORCEPROP 2 LAST CDS_LIB standard
J 0
(-200 825);
PAINT MONO (-200 825);
DISPLAY INVISIBLE (-200 825);
FORCEADD OFFPAGE..2
(-1400 3550);
FORCEPROP 2 LAST $XR0 208 
J 0
(-1211 3550);
DISPLAY 0.638298 (-1211 3550);
PAINT MONO (-1211 3550);
FORCEPROP 1 LAST OFFPAGE TRUE
J 0
(-1075 3425);
DISPLAY 0.872340 (-1075 3425);
PAINT GREEN (-1075 3425);
DISPLAY INVISIBLE (-1075 3425);
FORCEPROP 1 LAST COMMENT_BODY TRUE
J 0
(-1445 3455);
DISPLAY 0.872340 (-1445 3455);
PAINT GREEN (-1445 3455);
DISPLAY INVISIBLE (-1445 3455);
FORCEPROP 2 LAST CDS_LIB standard
J 0
(-1400 3550);
PAINT MONO (-1400 3550);
DISPLAY INVISIBLE (-1400 3550);
FORCEPROP 2 LAST PATH I42
J 0
(-1200 3600);
DISPLAY 1.021277 (-1200 3600);
DISPLAY INVISIBLE (-1200 3600);
FORCEADD OFFPAGE..1
(-4200 3550);
FORCEPROP 2 LAST $XR1 219 
J 0
(-4602 3550);
DISPLAY 0.638298 (-4602 3550);
PAINT MONO (-4602 3550);
FORCEPROP 2 LAST $XR0 215 
J 0
(-4482 3550);
DISPLAY 0.638298 (-4482 3550);
PAINT MONO (-4482 3550);
FORCEPROP 1 LAST OFFPAGE TRUE
J 0
(-3875 3425);
DISPLAY 0.872340 (-3875 3425);
DISPLAY INVISIBLE (-3875 3425);
FORCEPROP 1 LAST COMMENT_BODY TRUE
J 0
(-4075 3450);
DISPLAY 1.170213 (-4075 3450);
PAINT GREEN (-4075 3450);
DISPLAY INVISIBLE (-4075 3450);
FORCEPROP 2 LAST CDS_LIB standard
J 0
(-4200 3550);
PAINT MONO (-4200 3550);
DISPLAY INVISIBLE (-4200 3550);
FORCEPROP 2 LAST PATH I43
J 0
(-4475 3600);
DISPLAY 1.021277 (-4475 3600);
DISPLAY INVISIBLE (-4475 3600);
FORCEADD Q_RES..1
(-2800 3550);
FORCEPROP 1 LAST PART_NUMBER CS03322FB03
J 0
(-2900 3625);
DISPLAY 0.510638 (-2900 3625);
DISPLAY INVISIBLE (-2900 3625);
FORCEPROP 1 LAST MATERIAL CHIP
J 0
(-2525 3550);
DISPLAY 0.404255 (-2525 3550);
FORCEPROP 1 LAST TOLERANCE 1%
J 0
(-2600 3550);
DISPLAY 0.404255 (-2600 3550);
FORCEPROP 1 LAST VALUE 33.2
J 2
(-2625 3550);
DISPLAY 0.404255 (-2625 3550);
FORCEPROP 1 LAST WATTAGE 1/16W
J 2
(-2625 3675);
DISPLAY 0.510638 (-2625 3675);
FORCEPROP 1 LAST PACK_TYPE 0402LF
J 0
(-2900 3675);
DISPLAY 0.510638 (-2900 3675);
FORCEPROP 1 LAST $LOCATION R109
J 0
(-3025 3550);
DISPLAY 0.638298 (-3025 3550);
FORCEPROP 1 LASTPIN (-2900 3550) $PN 1
J 0
(-2888 3562);
DISPLAY 0.787234 (-2888 3562);
FORCEPROP 1 LASTPIN (-2700 3550) $PN 2
J 0
(-2738 3562);
DISPLAY 0.787234 (-2738 3562);
FORCEPROP 1 LAST PATH I44
J 0
(-2850 3700);
DISPLAY 0.978723 (-2850 3700);
PAINT WHITE (-2850 3700);
DISPLAY INVISIBLE (-2850 3700);
FORCEPROP 2 LAST CDS_LIB pure_quanta
J 0
(-2800 3550);
PAINT MONO (-2800 3550);
DISPLAY INVISIBLE (-2800 3550);
FORCEPROP 2 LAST CDS_LOCATION R109
J 0
(-2850 3750);
DISPLAY 1.021277 (-2850 3750);
DISPLAY INVISIBLE (-2850 3750);
FORCEPROP 2 LAST $SEC 1
J 0
(-2850 3750);
DISPLAY 0.680851 (-2850 3750);
PAINT MONO (-2850 3750);
DISPLAY INVISIBLE (-2850 3750);
FORCEPROP 2 LAST CDS_SEC 1
J 0
(-2850 3750);
DISPLAY 1.021277 (-2850 3750);
DISPLAY INVISIBLE (-2850 3750);
FORCEADD OFFPAGE..1
(450 3775);
FORCEPROP 2 LAST $XR0 216 
J 0
(198 3775);
DISPLAY 0.638298 (198 3775);
PAINT MONO (198 3775);
FORCEPROP 2 LAST PATH I45
J 0
(175 3825);
DISPLAY 1.021277 (175 3825);
DISPLAY INVISIBLE (175 3825);
FORCEPROP 1 LAST OFFPAGE TRUE
J 0
(775 3650);
DISPLAY 0.872340 (775 3650);
DISPLAY INVISIBLE (775 3650);
FORCEPROP 1 LAST COMMENT_BODY TRUE
J 0
(575 3675);
DISPLAY 1.170213 (575 3675);
PAINT GREEN (575 3675);
DISPLAY INVISIBLE (575 3675);
FORCEPROP 2 LAST CDS_LIB standard
J 0
(450 3775);
PAINT MONO (450 3775);
DISPLAY INVISIBLE (450 3775);
FORCEADD OFFPAGE..2
(3500 3775);
FORCEPROP 2 LAST $XR0 203 
J 0
(3689 3775);
DISPLAY 0.638298 (3689 3775);
PAINT MONO (3689 3775);
FORCEPROP 2 LAST PATH I46
J 0
(3700 3825);
DISPLAY 1.021277 (3700 3825);
DISPLAY INVISIBLE (3700 3825);
FORCEPROP 2 LAST CDS_LIB standard
J 0
(3500 3775);
PAINT MONO (3500 3775);
DISPLAY INVISIBLE (3500 3775);
FORCEPROP 1 LAST COMMENT_BODY TRUE
J 0
(3455 3680);
DISPLAY 0.872340 (3455 3680);
PAINT GREEN (3455 3680);
DISPLAY INVISIBLE (3455 3680);
FORCEPROP 1 LAST OFFPAGE TRUE
J 0
(3825 3650);
DISPLAY 0.872340 (3825 3650);
PAINT GREEN (3825 3650);
DISPLAY INVISIBLE (3825 3650);
FORCEADD OFFPAGE..2
(-1400 3775);
FORCEPROP 2 LAST $XR1 220 
J 0
(-1091 3775);
DISPLAY 0.638298 (-1091 3775);
PAINT MONO (-1091 3775);
FORCEPROP 2 LAST $XR0 182 
J 0
(-1211 3775);
DISPLAY 0.638298 (-1211 3775);
PAINT MONO (-1211 3775);
FORCEPROP 1 LAST OFFPAGE TRUE
J 0
(-1075 3650);
DISPLAY 0.872340 (-1075 3650);
PAINT GREEN (-1075 3650);
DISPLAY INVISIBLE (-1075 3650);
FORCEPROP 1 LAST COMMENT_BODY TRUE
J 0
(-1445 3680);
DISPLAY 0.872340 (-1445 3680);
PAINT GREEN (-1445 3680);
DISPLAY INVISIBLE (-1445 3680);
FORCEPROP 2 LAST CDS_LIB standard
J 0
(-1400 3775);
PAINT MONO (-1400 3775);
DISPLAY INVISIBLE (-1400 3775);
FORCEPROP 2 LAST PATH I49
J 0
(-1200 3825);
DISPLAY 1.021277 (-1200 3825);
DISPLAY INVISIBLE (-1200 3825);
FORCEADD OFFPAGE..1
(-4200 3150);
FORCEPROP 2 LAST $XR1 252 
J 0
(-4602 3150);
DISPLAY 0.638298 (-4602 3150);
PAINT MONO (-4602 3150);
FORCEPROP 2 LAST $XR0 182 
J 0
(-4482 3150);
DISPLAY 0.638298 (-4482 3150);
PAINT MONO (-4482 3150);
FORCEPROP 1 LAST COMMENT_BODY TRUE
J 0
(-4075 3050);
DISPLAY 1.170213 (-4075 3050);
PAINT GREEN (-4075 3050);
DISPLAY INVISIBLE (-4075 3050);
FORCEPROP 1 LAST OFFPAGE TRUE
J 0
(-3875 3025);
DISPLAY 0.872340 (-3875 3025);
DISPLAY INVISIBLE (-3875 3025);
FORCEPROP 2 LAST PATH I5
J 0
(-4150 3225);
DISPLAY 1.021277 (-4150 3225);
DISPLAY INVISIBLE (-4150 3225);
FORCEPROP 2 LAST CDS_LIB standard
J 0
(-4200 3150);
PAINT MONO (-4200 3150);
DISPLAY INVISIBLE (-4200 3150);
FORCEADD OFFPAGE..2
(3500 3575);
FORCEPROP 2 LAST $XR0 240 
J 0
(3689 3575);
DISPLAY 0.638298 (3689 3575);
PAINT MONO (3689 3575);
FORCEPROP 2 LAST PATH I53
J 0
(3700 3625);
DISPLAY 1.021277 (3700 3625);
DISPLAY INVISIBLE (3700 3625);
FORCEPROP 2 LAST CDS_LIB standard
J 0
(3500 3575);
PAINT MONO (3500 3575);
DISPLAY INVISIBLE (3500 3575);
FORCEPROP 1 LAST COMMENT_BODY TRUE
J 0
(3455 3480);
DISPLAY 0.872340 (3455 3480);
PAINT GREEN (3455 3480);
DISPLAY INVISIBLE (3455 3480);
FORCEPROP 1 LAST OFFPAGE TRUE
J 0
(3825 3450);
DISPLAY 0.872340 (3825 3450);
PAINT GREEN (3825 3450);
DISPLAY INVISIBLE (3825 3450);
FORCEADD OFFPAGE..1
(450 3575);
FORCEPROP 2 LAST $XR1 219 
J 0
(78 3575);
DISPLAY 0.638298 (78 3575);
PAINT MONO (78 3575);
FORCEPROP 2 LAST $XR0 215 
J 0
(198 3575);
DISPLAY 0.638298 (198 3575);
PAINT MONO (198 3575);
FORCEPROP 2 LAST PATH I54
J 0
(175 3625);
DISPLAY 1.021277 (175 3625);
DISPLAY INVISIBLE (175 3625);
FORCEPROP 2 LAST CDS_LIB standard
J 0
(450 3575);
PAINT MONO (450 3575);
DISPLAY INVISIBLE (450 3575);
FORCEPROP 1 LAST COMMENT_BODY TRUE
J 0
(575 3475);
DISPLAY 1.170213 (575 3475);
PAINT GREEN (575 3475);
DISPLAY INVISIBLE (575 3475);
FORCEPROP 1 LAST OFFPAGE TRUE
J 0
(775 3450);
DISPLAY 0.872340 (775 3450);
DISPLAY INVISIBLE (775 3450);
FORCEADD Q_RES..1
(1925 3575);
FORCEPROP 1 LAST PART_NUMBER CS03322FB03
J 0
(1825 3650);
DISPLAY 0.510638 (1825 3650);
DISPLAY INVISIBLE (1825 3650);
FORCEPROP 1 LAST PACK_TYPE 0402LF
J 0
(2225 3575);
DISPLAY 0.510638 (2225 3575);
FORCEPROP 1 LAST VALUE 33.2
J 2
(2125 3575);
DISPLAY 0.510638 (2125 3575);
FORCEPROP 1 LAST TOLERANCE 1%
J 0
(2150 3575);
DISPLAY 0.510638 (2150 3575);
FORCEPROP 1 LAST MATERIAL CHIP
J 0
(1825 3700);
DISPLAY 0.510638 (1825 3700);
FORCEPROP 1 LAST WATTAGE 1/16W
J 2
(2100 3700);
DISPLAY 0.510638 (2100 3700);
FORCEPROP 1 LAST $LOCATION R1469
J 0
(1675 3575);
DISPLAY 0.638298 (1675 3575);
FORCEPROP 1 LASTPIN (1825 3575) $PN 1
J 0
(1837 3587);
DISPLAY 0.787234 (1837 3587);
FORCEPROP 1 LASTPIN (2025 3575) $PN 2
J 0
(1987 3587);
DISPLAY 0.787234 (1987 3587);
FORCEPROP 2 LAST CDS_LIB pure_quanta
J 0
(1925 3575);
PAINT MONO (1925 3575);
DISPLAY INVISIBLE (1925 3575);
FORCEPROP 1 LAST PATH I55
J 0
(1875 3725);
DISPLAY 0.978723 (1875 3725);
PAINT WHITE (1875 3725);
DISPLAY INVISIBLE (1875 3725);
FORCEPROP 2 LAST CDS_LOCATION R1469
J 0
(1875 3775);
DISPLAY 1.021277 (1875 3775);
DISPLAY INVISIBLE (1875 3775);
FORCEPROP 2 LAST $SEC 1
J 0
(1875 3775);
DISPLAY 0.680851 (1875 3775);
PAINT MONO (1875 3775);
DISPLAY INVISIBLE (1875 3775);
FORCEPROP 2 LAST CDS_SEC 1
J 0
(1875 3775);
DISPLAY 1.021277 (1875 3775);
DISPLAY INVISIBLE (1875 3775);
FORCEADD Q_RES..1
(1925 3375);
FORCEPROP 1 LAST PART_NUMBER CS03322FB03
J 0
(1825 3450);
DISPLAY 0.510638 (1825 3450);
DISPLAY INVISIBLE (1825 3450);
FORCEPROP 1 LAST VALUE 33.2
J 2
(2125 3375);
DISPLAY 0.510638 (2125 3375);
FORCEPROP 1 LAST PACK_TYPE 0402LF
J 0
(2225 3375);
DISPLAY 0.510638 (2225 3375);
FORCEPROP 1 LAST TOLERANCE 1%
J 0
(2150 3375);
DISPLAY 0.510638 (2150 3375);
FORCEPROP 1 LAST WATTAGE 1/16W
J 2
(2100 3500);
DISPLAY 0.510638 (2100 3500);
FORCEPROP 1 LAST MATERIAL CHIP
J 0
(1825 3500);
DISPLAY 0.510638 (1825 3500);
FORCEPROP 1 LAST $LOCATION R1470
J 0
(1675 3375);
DISPLAY 0.638298 (1675 3375);
FORCEPROP 1 LASTPIN (1825 3375) $PN 1
J 0
(1837 3387);
DISPLAY 0.787234 (1837 3387);
FORCEPROP 1 LASTPIN (2025 3375) $PN 2
J 0
(1987 3387);
DISPLAY 0.787234 (1987 3387);
FORCEPROP 2 LAST CDS_LIB pure_quanta
J 0
(1925 3375);
PAINT MONO (1925 3375);
DISPLAY INVISIBLE (1925 3375);
FORCEPROP 1 LAST PATH I56
J 0
(1875 3525);
DISPLAY 0.978723 (1875 3525);
PAINT WHITE (1875 3525);
DISPLAY INVISIBLE (1875 3525);
FORCEPROP 2 LAST CDS_LOCATION R1470
J 0
(1875 3575);
DISPLAY 1.021277 (1875 3575);
DISPLAY INVISIBLE (1875 3575);
FORCEPROP 2 LAST $SEC 1
J 0
(1875 3575);
DISPLAY 0.680851 (1875 3575);
PAINT MONO (1875 3575);
DISPLAY INVISIBLE (1875 3575);
FORCEPROP 2 LAST CDS_SEC 1
J 0
(1875 3575);
DISPLAY 1.021277 (1875 3575);
DISPLAY INVISIBLE (1875 3575);
FORCEADD OFFPAGE..2
(3500 3375);
FORCEPROP 2 LAST $XR0 202 
J 0
(3689 3375);
DISPLAY 0.638298 (3689 3375);
PAINT MONO (3689 3375);
FORCEPROP 2 LAST CDS_LIB standard
J 0
(3500 3375);
PAINT MONO (3500 3375);
DISPLAY INVISIBLE (3500 3375);
FORCEPROP 1 LAST COMMENT_BODY TRUE
J 0
(3455 3280);
DISPLAY 0.872340 (3455 3280);
PAINT GREEN (3455 3280);
DISPLAY INVISIBLE (3455 3280);
FORCEPROP 1 LAST OFFPAGE TRUE
J 0
(3825 3250);
DISPLAY 0.872340 (3825 3250);
PAINT GREEN (3825 3250);
DISPLAY INVISIBLE (3825 3250);
FORCEPROP 2 LAST PATH I57
J 0
(3700 3425);
DISPLAY 1.021277 (3700 3425);
DISPLAY INVISIBLE (3700 3425);
FORCEADD OFFPAGE..1
(425 2875);
FORCEPROP 2 LAST $XR1 219 
J 0
(23 2875);
DISPLAY 0.638298 (23 2875);
PAINT MONO (23 2875);
FORCEPROP 2 LAST $XR0 214 
J 0
(143 2875);
DISPLAY 0.638298 (143 2875);
PAINT MONO (143 2875);
FORCEPROP 2 LAST PATH I59
J 0
(150 2925);
DISPLAY 1.021277 (150 2925);
DISPLAY INVISIBLE (150 2925);
FORCEPROP 2 LAST CDS_LIB standard
J 0
(425 2875);
PAINT MONO (425 2875);
DISPLAY INVISIBLE (425 2875);
FORCEPROP 1 LAST COMMENT_BODY TRUE
J 0
(550 2775);
DISPLAY 1.170213 (550 2775);
PAINT GREEN (550 2775);
DISPLAY INVISIBLE (550 2775);
FORCEPROP 1 LAST OFFPAGE TRUE
J 0
(750 2750);
DISPLAY 0.872340 (750 2750);
DISPLAY INVISIBLE (750 2750);
FORCEADD OFFPAGE..2
(-1400 3150);
FORCEPROP 2 LAST $XR0 214 
J 0
(-1211 3150);
DISPLAY 0.638298 (-1211 3150);
PAINT MONO (-1211 3150);
FORCEPROP 1 LAST COMMENT_BODY TRUE
J 0
(-1445 3055);
DISPLAY 0.872340 (-1445 3055);
PAINT GREEN (-1445 3055);
DISPLAY INVISIBLE (-1445 3055);
FORCEPROP 1 LAST OFFPAGE TRUE
J 0
(-1075 3025);
DISPLAY 0.872340 (-1075 3025);
PAINT GREEN (-1075 3025);
DISPLAY INVISIBLE (-1075 3025);
FORCEPROP 2 LAST PATH I6
J 0
(-1225 3225);
DISPLAY 1.021277 (-1225 3225);
DISPLAY INVISIBLE (-1225 3225);
FORCEPROP 2 LAST CDS_LIB standard
J 0
(-1400 3150);
PAINT MONO (-1400 3150);
DISPLAY INVISIBLE (-1400 3150);
FORCEADD Q_RES..1
(-2800 2925);
FORCEPROP 1 LAST PART_NUMBER CS03322FB03
J 0
(-2900 3000);
DISPLAY 0.510638 (-2900 3000);
DISPLAY INVISIBLE (-2900 3000);
FORCEPROP 1 LAST TOLERANCE 1%
J 0
(-2600 2925);
DISPLAY 0.404255 (-2600 2925);
FORCEPROP 1 LAST VALUE 33.2
J 2
(-2625 2925);
DISPLAY 0.404255 (-2625 2925);
FORCEPROP 1 LAST WATTAGE 1/16W
J 2
(-2625 3050);
DISPLAY 0.510638 (-2625 3050);
FORCEPROP 1 LAST MATERIAL CHIP
J 0
(-2525 2925);
DISPLAY 0.404255 (-2525 2925);
FORCEPROP 1 LAST PACK_TYPE 0402LF
J 0
(-2900 3050);
DISPLAY 0.510638 (-2900 3050);
FORCEPROP 1 LAST $LOCATION R1205
J 0
(-3025 2925);
DISPLAY 0.638298 (-3025 2925);
FORCEPROP 1 LASTPIN (-2900 2925) $PN 1
J 0
(-2888 2937);
DISPLAY 0.787234 (-2888 2937);
FORCEPROP 1 LASTPIN (-2700 2925) $PN 2
J 0
(-2738 2937);
DISPLAY 0.787234 (-2738 2937);
FORCEPROP 2 LAST CDS_LIB pure_quanta
J 0
(-2800 2925);
PAINT MONO (-2800 2925);
DISPLAY INVISIBLE (-2800 2925);
FORCEPROP 1 LAST PATH I7
J 0
(-2850 3075);
DISPLAY 0.978723 (-2850 3075);
PAINT WHITE (-2850 3075);
DISPLAY INVISIBLE (-2850 3075);
FORCEPROP 2 LAST CDS_LOCATION R1205
J 0
(-2850 3125);
DISPLAY 1.021277 (-2850 3125);
DISPLAY INVISIBLE (-2850 3125);
FORCEPROP 2 LAST $SEC 1
J 0
(-2850 3125);
DISPLAY 0.680851 (-2850 3125);
PAINT MONO (-2850 3125);
DISPLAY INVISIBLE (-2850 3125);
FORCEPROP 2 LAST CDS_SEC 1
J 0
(-2850 3125);
DISPLAY 1.021277 (-2850 3125);
DISPLAY INVISIBLE (-2850 3125);
FORCEADD OFFPAGE..1
(325 925);
FORCEPROP 2 LAST $XR1 219 
J 0
(-77 925);
DISPLAY 0.638298 (-77 925);
PAINT MONO (-77 925);
FORCEPROP 2 LAST $XR0 214 
J 0
(43 925);
DISPLAY 0.638298 (43 925);
PAINT MONO (43 925);
FORCEPROP 2 LAST PATH I73
J 0
(50 975);
DISPLAY 1.021277 (50 975);
DISPLAY INVISIBLE (50 975);
FORCEPROP 1 LAST OFFPAGE TRUE
J 0
(650 800);
DISPLAY 0.872340 (650 800);
DISPLAY INVISIBLE (650 800);
FORCEPROP 1 LAST COMMENT_BODY TRUE
J 0
(450 825);
DISPLAY 1.170213 (450 825);
PAINT GREEN (450 825);
DISPLAY INVISIBLE (450 825);
FORCEPROP 2 LAST CDS_LIB standard
J 0
(325 925);
PAINT MONO (325 925);
DISPLAY INVISIBLE (325 925);
FORCEADD OFFPAGE..1
(-4200 2925);
FORCEPROP 2 LAST $XR1 255 
J 0
(-4602 2925);
DISPLAY 0.638298 (-4602 2925);
PAINT MONO (-4602 2925);
FORCEPROP 2 LAST $XR0 183 
J 0
(-4482 2925);
DISPLAY 0.638298 (-4482 2925);
PAINT MONO (-4482 2925);
FORCEPROP 1 LAST OFFPAGE TRUE
J 0
(-3875 2800);
DISPLAY 0.872340 (-3875 2800);
DISPLAY INVISIBLE (-3875 2800);
FORCEPROP 1 LAST COMMENT_BODY TRUE
J 0
(-4075 2825);
DISPLAY 1.170213 (-4075 2825);
PAINT GREEN (-4075 2825);
DISPLAY INVISIBLE (-4075 2825);
FORCEPROP 2 LAST CDS_LIB standard
J 0
(-4200 2925);
PAINT MONO (-4200 2925);
DISPLAY INVISIBLE (-4200 2925);
FORCEPROP 2 LAST PATH I8
J 0
(-4150 3000);
DISPLAY 1.021277 (-4150 3000);
DISPLAY INVISIBLE (-4150 3000);
FORCEADD Q_RES..1
(-2800 3350);
FORCEPROP 1 LAST PART_NUMBER CS03322FB03
J 0
(-2900 3425);
DISPLAY 0.510638 (-2900 3425);
DISPLAY INVISIBLE (-2900 3425);
FORCEPROP 1 LAST TOLERANCE 1%
J 0
(-2600 3350);
DISPLAY 0.404255 (-2600 3350);
FORCEPROP 1 LAST VALUE 33.2
J 2
(-2625 3350);
DISPLAY 0.404255 (-2625 3350);
FORCEPROP 1 LAST WATTAGE 1/16W
J 2
(-2625 3475);
DISPLAY 0.510638 (-2625 3475);
FORCEPROP 1 LAST MATERIAL CHIP
J 0
(-2525 3350);
DISPLAY 0.404255 (-2525 3350);
FORCEPROP 1 LAST PACK_TYPE 0402LF
J 0
(-2900 3475);
DISPLAY 0.510638 (-2900 3475);
FORCEPROP 1 LAST $LOCATION R1995
J 0
(-3025 3350);
DISPLAY 0.638298 (-3025 3350);
FORCEPROP 1 LASTPIN (-2900 3350) $PN 1
J 0
(-2888 3362);
DISPLAY 0.787234 (-2888 3362);
FORCEPROP 1 LASTPIN (-2700 3350) $PN 2
J 0
(-2738 3362);
DISPLAY 0.787234 (-2738 3362);
FORCEPROP 1 LAST PATH I86
J 0
(-2850 3500);
DISPLAY 0.978723 (-2850 3500);
PAINT WHITE (-2850 3500);
DISPLAY INVISIBLE (-2850 3500);
FORCEPROP 2 LAST CDS_LIB pure_quanta
J 0
(-2800 3350);
PAINT MONO (-2800 3350);
DISPLAY INVISIBLE (-2800 3350);
FORCEPROP 0 LAST CDS_LOCATION R1995
J 0
(-2625 3500);
DISPLAY 1.021277 (-2625 3500);
DISPLAY INVISIBLE (-2625 3500);
FORCEPROP 2 LAST $SEC 1
J 0
(-2850 3550);
DISPLAY 0.680851 (-2850 3550);
PAINT MONO (-2850 3550);
DISPLAY INVISIBLE (-2850 3550);
FORCEPROP 2 LAST CDS_SEC 1
J 0
(-2850 3550);
DISPLAY 1.021277 (-2850 3550);
DISPLAY INVISIBLE (-2850 3550);
FORCEADD Q_RES..1
(-2800 3150);
FORCEPROP 1 LAST PART_NUMBER CS03322FB03
J 0
(-2900 3225);
DISPLAY 0.510638 (-2900 3225);
DISPLAY INVISIBLE (-2900 3225);
FORCEPROP 1 LAST TOLERANCE 1%
J 0
(-2600 3150);
DISPLAY 0.404255 (-2600 3150);
FORCEPROP 1 LAST VALUE 33.2
J 2
(-2625 3150);
DISPLAY 0.404255 (-2625 3150);
FORCEPROP 1 LAST WATTAGE 1/16W
J 2
(-2625 3275);
DISPLAY 0.510638 (-2625 3275);
FORCEPROP 1 LAST PACK_TYPE 0402LF
J 0
(-2900 3275);
DISPLAY 0.510638 (-2900 3275);
FORCEPROP 1 LAST MATERIAL CHIP
J 0
(-2525 3150);
DISPLAY 0.404255 (-2525 3150);
FORCEPROP 1 LAST $LOCATION R1996
J 0
(-3025 3150);
DISPLAY 0.638298 (-3025 3150);
FORCEPROP 1 LASTPIN (-2900 3150) $PN 1
J 0
(-2888 3162);
DISPLAY 0.787234 (-2888 3162);
FORCEPROP 1 LASTPIN (-2700 3150) $PN 2
J 0
(-2738 3162);
DISPLAY 0.787234 (-2738 3162);
FORCEPROP 1 LAST PATH I87
J 0
(-2850 3300);
DISPLAY 0.978723 (-2850 3300);
PAINT WHITE (-2850 3300);
DISPLAY INVISIBLE (-2850 3300);
FORCEPROP 2 LAST CDS_LIB pure_quanta
J 0
(-2800 3150);
PAINT MONO (-2800 3150);
DISPLAY INVISIBLE (-2800 3150);
FORCEPROP 0 LAST CDS_LOCATION R1996
J 0
(-2625 3300);
DISPLAY 1.021277 (-2625 3300);
DISPLAY INVISIBLE (-2625 3300);
FORCEPROP 2 LAST $SEC 1
J 0
(-2850 3350);
DISPLAY 0.680851 (-2850 3350);
PAINT MONO (-2850 3350);
DISPLAY INVISIBLE (-2850 3350);
FORCEPROP 2 LAST CDS_SEC 1
J 0
(-2850 3350);
DISPLAY 1.021277 (-2850 3350);
DISPLAY INVISIBLE (-2850 3350);
FORCEADD OFFPAGE..2
(3475 -550);
FORCEPROP 2 LAST $XR0 215 
J 0
(3664 -550);
DISPLAY 0.638298 (3664 -550);
PAINT MONO (3664 -550);
FORCEPROP 2 LAST PATH I88
J 0
(3675 -500);
DISPLAY 1.021277 (3675 -500);
DISPLAY INVISIBLE (3675 -500);
FORCEPROP 2 LAST CDS_LIB standard
J 0
(3475 -550);
PAINT MONO (3475 -550);
DISPLAY INVISIBLE (3475 -550);
FORCEPROP 1 LAST COMMENT_BODY TRUE
J 0
(3430 -645);
DISPLAY 0.872340 (3430 -645);
PAINT GREEN (3430 -645);
DISPLAY INVISIBLE (3430 -645);
FORCEPROP 1 LAST OFFPAGE TRUE
J 0
(3800 -675);
DISPLAY 0.872340 (3800 -675);
PAINT GREEN (3800 -675);
DISPLAY INVISIBLE (3800 -675);
FORCEADD OFFPAGE..2
(-1400 2925);
FORCEPROP 2 LAST $XR0 215 
J 0
(-1211 2925);
DISPLAY 0.638298 (-1211 2925);
PAINT MONO (-1211 2925);
FORCEPROP 1 LAST OFFPAGE TRUE
J 0
(-1075 2800);
DISPLAY 0.872340 (-1075 2800);
PAINT GREEN (-1075 2800);
DISPLAY INVISIBLE (-1075 2800);
FORCEPROP 1 LAST COMMENT_BODY TRUE
J 0
(-1445 2830);
DISPLAY 0.872340 (-1445 2830);
PAINT GREEN (-1445 2830);
DISPLAY INVISIBLE (-1445 2830);
FORCEPROP 2 LAST CDS_LIB standard
J 0
(-1400 2925);
PAINT MONO (-1400 2925);
DISPLAY INVISIBLE (-1400 2925);
FORCEPROP 2 LAST PATH I9
J 0
(-1225 3000);
DISPLAY 1.021277 (-1225 3000);
DISPLAY INVISIBLE (-1225 3000);
FORCEADD OFFPAGE..1
(425 -550);
FORCEPROP 2 LAST $XR1 198 
J 0
(23 -550);
DISPLAY 0.638298 (23 -550);
PAINT MONO (23 -550);
FORCEPROP 2 LAST $XR0 183 
J 0
(143 -550);
DISPLAY 0.638298 (143 -550);
PAINT MONO (143 -550);
FORCEPROP 2 LAST PATH I90
J 0
(150 -500);
DISPLAY 1.021277 (150 -500);
DISPLAY INVISIBLE (150 -500);
FORCEPROP 1 LAST OFFPAGE TRUE
J 0
(750 -675);
DISPLAY 0.872340 (750 -675);
DISPLAY INVISIBLE (750 -675);
FORCEPROP 1 LAST COMMENT_BODY TRUE
J 0
(550 -650);
DISPLAY 1.170213 (550 -650);
PAINT GREEN (550 -650);
DISPLAY INVISIBLE (550 -650);
FORCEPROP 2 LAST CDS_LIB standard
J 0
(425 -550);
PAINT MONO (425 -550);
DISPLAY INVISIBLE (425 -550);
FORCEADD Q_RES..1
(1875 -550);
FORCEPROP 1 LAST PART_NUMBER CS03322FB03
J 0
(1775 -475);
DISPLAY 0.510638 (1775 -475);
DISPLAY INVISIBLE (1775 -475);
FORCEPROP 1 LAST WATTAGE 1/16W
J 2
(2050 -425);
DISPLAY 0.510638 (2050 -425);
FORCEPROP 1 LAST PACK_TYPE 0402LF
J 0
(2175 -550);
DISPLAY 0.510638 (2175 -550);
FORCEPROP 1 LAST TOLERANCE 1%
J 0
(2100 -550);
DISPLAY 0.510638 (2100 -550);
FORCEPROP 1 LAST VALUE 33.2
J 2
(2075 -550);
DISPLAY 0.510638 (2075 -550);
FORCEPROP 1 LAST MATERIAL CHIP
J 0
(1775 -425);
DISPLAY 0.510638 (1775 -425);
FORCEPROP 1 LAST $LOCATION R269
J 0
(1625 -550);
DISPLAY 0.638298 (1625 -550);
FORCEPROP 1 LASTPIN (1775 -550) $PN 1
J 0
(1787 -538);
DISPLAY 0.787234 (1787 -538);
FORCEPROP 1 LASTPIN (1975 -550) $PN 2
J 0
(1937 -538);
DISPLAY 0.787234 (1937 -538);
FORCEPROP 1 LAST PATH I91
J 0
(1825 -400);
DISPLAY 0.978723 (1825 -400);
PAINT WHITE (1825 -400);
DISPLAY INVISIBLE (1825 -400);
FORCEPROP 2 LAST CDS_LIB pure_quanta
J 0
(1875 -550);
PAINT MONO (1875 -550);
DISPLAY INVISIBLE (1875 -550);
FORCEPROP 2 LAST CDS_LOCATION R269
J 0
(1825 -350);
DISPLAY 1.021277 (1825 -350);
DISPLAY INVISIBLE (1825 -350);
FORCEPROP 2 LAST $SEC 1
J 0
(1825 -350);
DISPLAY 0.680851 (1825 -350);
PAINT MONO (1825 -350);
DISPLAY INVISIBLE (1825 -350);
FORCEPROP 2 LAST CDS_SEC 1
J 0
(1825 -350);
DISPLAY 1.021277 (1825 -350);
DISPLAY INVISIBLE (1825 -350);
FORCEADD Q_RES..1
(-3775 2750);
FORCEPROP 1 LAST PART_NUMBER CS41002FB09
J 0
(-3900 2800);
DISPLAY 0.510638 (-3900 2800);
DISPLAY INVISIBLE (-3900 2800);
FORCEPROP 1 LAST MATERIAL CHIP
J 0
(-3475 2750);
DISPLAY 0.510638 (-3475 2750);
FORCEPROP 1 LAST VALUE 100K
J 2
(-3575 2750);
DISPLAY 0.510638 (-3575 2750);
FORCEPROP 1 LAST TOLERANCE 1%
J 0
(-3550 2750);
DISPLAY 0.510638 (-3550 2750);
FORCEPROP 1 LAST PACK_TYPE 0402LF
J 0
(-3900 2850);
DISPLAY 0.510638 (-3900 2850);
FORCEPROP 1 LAST WATTAGE 1/16W
J 2
(-3575 2850);
DISPLAY 0.510638 (-3575 2850);
FORCEPROP 1 LAST $LOCATION R1541
J 0
(-4050 2750);
DISPLAY 0.638298 (-4050 2750);
FORCEPROP 1 LASTPIN (-3875 2750) $PN 1
J 0
(-3863 2762);
DISPLAY 0.787234 (-3863 2762);
FORCEPROP 1 LASTPIN (-3675 2750) $PN 2
J 0
(-3713 2762);
DISPLAY 0.787234 (-3713 2762);
FORCEPROP 1 LAST PATH I92
J 0
(-3825 2900);
DISPLAY 0.978723 (-3825 2900);
PAINT WHITE (-3825 2900);
DISPLAY INVISIBLE (-3825 2900);
FORCEPROP 2 LAST CDS_LIB pure_quanta
J 0
(-3775 2750);
PAINT MONO (-3775 2750);
DISPLAY INVISIBLE (-3775 2750);
FORCEPROP 2 LAST CDS_LOCATION R1541
J 0
(-3825 2950);
DISPLAY 1.021277 (-3825 2950);
DISPLAY INVISIBLE (-3825 2950);
FORCEPROP 2 LAST $SEC 1
J 0
(-3825 2950);
DISPLAY 0.680851 (-3825 2950);
PAINT MONO (-3825 2950);
DISPLAY INVISIBLE (-3825 2950);
FORCEPROP 2 LAST CDS_SEC 1
J 0
(-3825 2950);
DISPLAY 1.021277 (-3825 2950);
DISPLAY INVISIBLE (-3825 2950);
FORCEADD UNIVERSAL_GND..1
(-4150 2650);
FORCEPROP 3 LASTPIN (-4150 2700) SIG_NAME GND\g
J 0
(-4140 2710);
DISPLAY 0.659574 (-4140 2710);
PAINT MONO (-4140 2710);
DISPLAY INVISIBLE (-4140 2710);
FORCEPROP 2 LAST CDS_LIB logical_power
J 0
(-4150 2650);
PAINT MONO (-4150 2650);
DISPLAY INVISIBLE (-4150 2650);
FORCEPROP 1 LAST PATH I93
J 0
(-4075 2650);
DISPLAY 0.872340 (-4075 2650);
PAINT AQUA (-4075 2650);
DISPLAY INVISIBLE (-4075 2650);
FORCEPROP 1 LAST HDL_POWER GND
J 1
(-4125 2575);
DISPLAY 0.872340 (-4125 2575);
PAINT GREEN (-4125 2575);
DISPLAY INVISIBLE (-4125 2575);
FORCEADD Q_RES..1
(-2800 3775);
FORCEPROP 1 LAST PART_NUMBER CS00002JB13
J 0
(-2900 3825);
DISPLAY 0.404255 (-2900 3825);
DISPLAY INVISIBLE (-2900 3825);
FORCEPROP 1 LAST TOLERANCE 5%
J 0
(-2600 3775);
DISPLAY 0.404255 (-2600 3775);
FORCEPROP 1 LAST VALUE 0
J 2
(-2650 3775);
DISPLAY 0.404255 (-2650 3775);
FORCEPROP 1 LAST WATTAGE 1/16W
J 2
(-2675 3850);
DISPLAY 0.404255 (-2675 3850);
FORCEPROP 1 LAST MATERIAL CHIP
J 0
(-2525 3775);
DISPLAY 0.404255 (-2525 3775);
FORCEPROP 1 LAST PACK_TYPE 0402LF
J 0
(-2900 3850);
DISPLAY 0.404255 (-2900 3850);
FORCEPROP 1 LAST $LOCATION R1744
J 0
(-3025 3775);
DISPLAY 0.638298 (-3025 3775);
FORCEPROP 1 LASTPIN (-2900 3775) $PN 1
J 0
(-2888 3787);
DISPLAY 0.787234 (-2888 3787);
FORCEPROP 1 LASTPIN (-2700 3775) $PN 2
J 0
(-2738 3787);
DISPLAY 0.787234 (-2738 3787);
FORCEPROP 2 LAST CDS_LIB pure_quanta
J 0
(-2800 3775);
PAINT MONO (-2800 3775);
DISPLAY INVISIBLE (-2800 3775);
FORCEPROP 1 LAST PATH I94
J 0
(-2850 3925);
DISPLAY 0.978723 (-2850 3925);
PAINT WHITE (-2850 3925);
DISPLAY INVISIBLE (-2850 3925);
FORCEPROP 2 LAST CDS_LOCATION R1744
J 0
(-2850 3975);
DISPLAY 1.021277 (-2850 3975);
DISPLAY INVISIBLE (-2850 3975);
FORCEPROP 2 LAST $SEC 1
J 0
(-2850 3975);
DISPLAY 0.680851 (-2850 3975);
PAINT MONO (-2850 3975);
DISPLAY INVISIBLE (-2850 3975);
FORCEPROP 2 LAST CDS_SEC 1
J 0
(-2850 3975);
DISPLAY 1.021277 (-2850 3975);
DISPLAY INVISIBLE (-2850 3975);
FORCEADD OFFPAGE..1
(-4200 3775);
FORCEPROP 2 LAST $XR0 240 
J 0
(-4482 3775);
DISPLAY 0.638298 (-4482 3775);
PAINT MONO (-4482 3775);
FORCEPROP 2 LAST PATH I95
J 0
(-4500 3825);
DISPLAY 1.021277 (-4500 3825);
DISPLAY INVISIBLE (-4500 3825);
FORCEPROP 1 LAST OFFPAGE TRUE
J 0
(-3875 3650);
DISPLAY 0.872340 (-3875 3650);
DISPLAY INVISIBLE (-3875 3650);
FORCEPROP 1 LAST COMMENT_BODY TRUE
J 0
(-4075 3675);
DISPLAY 1.170213 (-4075 3675);
PAINT GREEN (-4075 3675);
DISPLAY INVISIBLE (-4075 3675);
FORCEPROP 2 LAST CDS_LIB standard
J 0
(-4200 3775);
PAINT MONO (-4200 3775);
DISPLAY INVISIBLE (-4200 3775);
FORCEADD OFFPAGE..1
R 2
(-1400 2500);
FORCEPROP 2 LAST $XR0 240 
J 0
(-1214 2500);
DISPLAY 0.638298 (-1214 2500);
PAINT MONO (-1214 2500);
FORCEPROP 2 LAST CDS_LIB standard
J 0
(-1400 2500);
DISPLAY INVISIBLE (-1400 2500);
FORCEPROP 2 LAST PATH I96
J 0
(-1200 2550);
DISPLAY 1.021277 (-1200 2550);
DISPLAY INVISIBLE (-1200 2550);
FORCEPROP 1 LAST OFFPAGE TRUE
J 2
(-1725 2375);
DISPLAY 1.170213 (-1725 2375);
PAINT GREEN (-1725 2375);
DISPLAY INVISIBLE (-1725 2375);
FORCEPROP 1 LAST COMMENT_BODY TRUE
J 2
(-1525 2400);
DISPLAY 1.170213 (-1525 2400);
PAINT GREEN (-1525 2400);
DISPLAY INVISIBLE (-1525 2400);
FORCEADD OFFPAGE..5
(-4200 2500);
FORCEPROP 2 LAST $XR1 215 
J 0
(-4575 2500);
DISPLAY 0.638298 (-4575 2500);
PAINT MONO (-4575 2500);
FORCEPROP 2 LAST $XR0 216 
J 0
(-4455 2500);
DISPLAY 0.638298 (-4455 2500);
PAINT MONO (-4455 2500);
FORCEPROP 2 LAST CDS_LIB standard
J 0
(-4200 2500);
DISPLAY INVISIBLE (-4200 2500);
FORCEPROP 2 LAST PATH I97
J 0
(-4475 2550);
DISPLAY 1.021277 (-4475 2550);
DISPLAY INVISIBLE (-4475 2550);
FORCEPROP 1 LAST OFFPAGE TRUE
J 0
(-3875 2375);
DISPLAY 0.872340 (-3875 2375);
PAINT GREEN (-3875 2375);
DISPLAY INVISIBLE (-3875 2375);
FORCEPROP 1 LAST COMMENT_BODY TRUE
J 0
(-4100 2425);
DISPLAY 0.872340 (-4100 2425);
PAINT PEACH (-4100 2425);
DISPLAY INVISIBLE (-4100 2425);
FORCEADD QUANTA_TITLE_BLOCK_C..1
(4300 -2225);
FORCEPROP 0 LAST CDS_CON_LAST_MODIFIED Fri Aug 25 14:03:44 2023
J 0
(2415 -2210);
PAINT MONO (2415 -2210);
DISPLAY INVISIBLE (2415 -2210);
FORCEPROP 2 LAST CUSTOM_TXT_CDS <XR_PAGE_TITLE>
J 0
(-3590 3025);
DISPLAY 0.638298 (-3590 3025);
PAINT PINK (-3590 3025);
DISPLAY INVISIBLE (-3590 3025);
FORCEPROP 2 LAST CUSTOM_TXT_CDS <CON_LAST_MODIFIED>
J 0
(2415 -2210);
DISPLAY 0.978723 (2415 -2210);
FORCEPROP 2 LAST CUSTOM_TXT_CDS <NAME_2>
J 0
(1125 -2175);
FORCEPROP 2 LAST CUSTOM_TXT_CDS <NAME_1>
J 0
(1125 -2050);
FORCEPROP 2 LAST CUSTOM_TXT_CDS <Q_NUMBER>
J 0
(2897 -2122);
DISPLAY 1.212766 (2897 -2122);
FORCEPROP 2 LAST CUSTOM_TXT_CDS <Q_PROJ>
J 0
(1918 -2123);
DISPLAY 1.212766 (1918 -2123);
FORCEPROP 2 LAST CUSTOM_TXT_CDS <Q_REV>
J 0
(4116 -2122);
DISPLAY 1.212766 (4116 -2122);
FORCEPROP 2 LAST CUSTOM_TXT_CDS <CON_PAGE_NUM> OF <CON_TOTAL_PAGES>
J 0
(3854 -2207);
DISPLAY 0.978723 (3854 -2207);
FORCEPROP 1 LAST Q_TITLE MAIN FPGA / PFR - SI (2/2)
J 0
(-4991 -2199);
DISPLAY 2.446809 (-4991 -2199);
PAINT GREEN (-4991 -2199);
FORCEPROP 1 LAST Q_DEPT 
J 1
(537 -2176);
DISPLAY 1.957447 (537 -2176);
PAINT GREEN (537 -2176);
FORCEPROP 2 LAST CDS_XR_PAGE_TITLE CR-223 : @S9S_MB_2U_LIB.S9S_MB_2U(SCH_1):PAGE223
J 0
(-3590 3025);
DISPLAY 0.638298 (-3590 3025);
PAINT PINK (-3590 3025);
DISPLAY INVISIBLE (-3590 3025);
FORCEPROP 2 LAST CDS_LIB pure_quanta
J 0
(4300 -2225);
PAINT MONO (4300 -2225);
DISPLAY INVISIBLE (4300 -2225);
FORCEPROP 1 LAST CDS_LMAN_SYM_OUTLINE -9475,6775,100,-125
J 0
(4300 -2225);
DISPLAY 0.468085 (4300 -2225);
PAINT GREEN (4300 -2225);
DISPLAY INVISIBLE (4300 -2225);
FORCEPROP 1 LAST COMMENT_BODY TRUE
J 0
(4312 -2238);
DISPLAY 0.978723 (4312 -2238);
PAINT GREEN (4312 -2238);
DISPLAY INVISIBLE (4312 -2238);
FORCEPROP 2 LAST PAGE_BORDER TRUE
J 0
(-3590 3025);
DISPLAY 0.638298 (-3590 3025);
PAINT PINK (-3590 3025);
DISPLAY INVISIBLE (-3590 3025);
WIRE 16 -1 (-2750 1225)(-2750 1175);
WIRE 16 -1 (-2750 325)(-2750 475);
WIRE 16 -1 (-4150 2700)(-4150 2750);
WIRE 16 2175 (-150 475)(1525 475);
WIRE 16 2175 (1525 475)(1525 175);
WIRE 16 2175 (-150 475)(-150 175);
WIRE 16 2175 (-150 175)(1525 175);
WIRE 16 -1 (375 300)(1800 300);
FORCEPROP 0 LAST CDS_PHYS_NET_NAME RST_PCIE_RISER2_N
J 0
(400 342);
PAINT MONO (400 342);
DISPLAY INVISIBLE (400 342);
FORCEPROP 0 LAST SIG_NAME RST_PERST_SWB_N
J 0
(840 310);
DISPLAY 0.702128 (840 310);
PAINT WHITE (840 310);
WIRE 16 -1 (375 925)(1800 925);
FORCEPROP 0 LAST CDS_PHYS_NET_NAME RST_PLTRST_N
J 0
(400 967);
PAINT MONO (400 967);
DISPLAY INVISIBLE (400 967);
FORCEPROP 0 LAST SIG_NAME RST_PCIE_CPU1_DEV_PERST_N
J 0
(475 935);
DISPLAY 0.702128 (475 935);
PAINT WHITE (475 935);
WIRE 16 2175 (1575 1125)(2400 1125);
WIRE 16 2175 (2400 1125)(2400 825);
WIRE 16 2175 (1575 1125)(1575 825);
WIRE 16 2175 (1575 825)(2400 825);
WIRE 16 -1 (2000 300)(3425 300);
FORCEPROP 0 LAST CDS_PHYS_NET_NAME RST_PCIE_RISER2_N
J 0
(2025 342);
PAINT MONO (2025 342);
DISPLAY INVISIBLE (2025 342);
FORCEPROP 0 LAST SIG_NAME RST_PERST_SWB_R_N
J 0
(2465 310);
DISPLAY 0.702128 (2465 310);
PAINT WHITE (2465 310);
WIRE 16 -1 (-250 825)(-1450 825);
FORCEPROP 2 LAST SIG_NAME FM_DB2000_OE_N
J 0
(-885 835);
DISPLAY 0.680851 (-885 835);
PAINT WHITE (-885 835);
WIRE 16 -1 (2000 925)(3425 925);
FORCEPROP 0 LAST CDS_PHYS_NET_NAME RST_PCIE_EDSFF3_PERST_N
J 0
(2025 967);
PAINT MONO (2025 967);
DISPLAY INVISIBLE (2025 967);
FORCEPROP 0 LAST SIG_NAME RST_OCP_V3_2_N
J 0
(2475 935);
DISPLAY 0.702128 (2475 935);
PAINT WHITE (2475 935);
WIRE 16 -1 (-2750 975)(-2750 825);
WIRE 16 -1 (-2750 825)(-2750 775);
WIRE 16 -1 (-1650 825)(-2750 825);
FORCEPROP 2 LAST SIG_NAME FM_PLD_CLKS_OE_R_N
J 0
(-2560 835);
DISPLAY 0.680851 (-2560 835);
PAINT WHITE (-2560 835);
WIRE 16 2175 (-2925 1375)(-2500 1375);
WIRE 16 2175 (-2500 1375)(-2500 1125);
WIRE 16 2175 (-2925 1375)(-2925 1125);
WIRE 16 2175 (-2925 1125)(-2500 1125);
WIRE 16 2175 (1600 3950)(2325 3950);
WIRE 16 2175 (2325 3950)(2325 3750);
WIRE 16 2175 (1600 3950)(1600 3750);
WIRE 16 2175 (1600 3750)(2325 3750);
WIRE 16 -1 (2025 3775)(3450 3775);
FORCEPROP 0 LAST CDS_PHYS_NET_NAME FM_SLPS3_GF_N
J 0
(2050 3817);
PAINT MONO (2050 3817);
DISPLAY INVISIBLE (2050 3817);
FORCEPROP 0 LAST SIG_NAME FM_THERMTRIP_DLY_LVC1_N
J 0
(2500 3785);
DISPLAY 0.702128 (2500 3785);
PAINT WHITE (2500 3785);
WIRE 16 -1 (1525 3375)(1825 3375);
WIRE 16 -1 (1525 3575)(1525 3375);
WIRE 16 -1 (1525 3575)(1825 3575);
WIRE 16 -1 (500 3575)(1525 3575);
FORCEPROP 0 LAST CDS_PHYS_NET_NAME RST_PLTRST_N
J 0
(525 3617);
PAINT MONO (525 3617);
DISPLAY INVISIBLE (525 3617);
FORCEPROP 0 LAST SIG_NAME RST_PLTRST_PLD_B_N
J 0
(600 3585);
DISPLAY 0.702128 (600 3585);
PAINT WHITE (600 3585);
WIRE 16 -1 (-4150 3775)(-2900 3775);
FORCEPROP 0 LAST CDS_PHYS_NET_NAME FM_PCH_SLP_S3_N
J 0
(-4125 3817);
PAINT MONO (-4125 3817);
DISPLAY INVISIBLE (-4125 3817);
FORCEPROP 0 LAST SIG_NAME FM_BMC_PWRBTN_OUT_N
J 0
(-3950 3785);
DISPLAY 0.702128 (-3950 3785);
PAINT WHITE (-3950 3785);
WIRE 16 -1 (-2700 3350)(-1450 3350);
FORCEPROP 0 LAST CDS_PHYS_NET_NAME FM_SLPS3_GF_N
J 0
(-2675 3392);
PAINT MONO (-2675 3392);
DISPLAY INVISIBLE (-2675 3392);
FORCEPROP 0 LAST SIG_NAME FM_SLPS3_PLD_N
J 0
(-2225 3360);
DISPLAY 0.702128 (-2225 3360);
PAINT WHITE (-2225 3360);
WIRE 16 -1 (500 3775)(1825 3775);
FORCEPROP 0 LAST CDS_PHYS_NET_NAME FM_PCH_SLP_S3_N
J 0
(525 3817);
PAINT MONO (525 3817);
DISPLAY INVISIBLE (525 3817);
FORCEPROP 0 LAST SIG_NAME FM_THERMTRIP_DLY_LVC1_R_N
J 0
(600 3785);
DISPLAY 0.702128 (600 3785);
PAINT WHITE (600 3785);
WIRE 16 -1 (-2900 575)(-4150 575);
FORCEPROP 2 LAST SIG_NAME FM_PLD_CLKS_DEV_EN
J 0
(-3960 585);
DISPLAY 0.680851 (-3960 585);
PAINT WHITE (-3960 585);
WIRE 16 -1 (-2900 1575)(-4150 1575);
FORCEPROP 2 LAST SIG_NAME FM_PLD_CLKS_DEV_R_EN
J 0
(-3960 1585);
DISPLAY 0.680851 (-3960 1585);
PAINT WHITE (-3960 1585);
WIRE 16 -1 (-2700 1575)(-1450 1575);
FORCEPROP 0 LAST CDS_PHYS_NET_NAME FM_SLPS3_GF_N
J 0
(-2675 1617);
PAINT MONO (-2675 1617);
DISPLAY INVISIBLE (-2675 1617);
FORCEPROP 0 LAST SIG_NAME FM_PLD_CLKS_DEV_EN
J 0
(-2225 1585);
DISPLAY 0.702128 (-2225 1585);
PAINT WHITE (-2225 1585);
WIRE 16 -1 (-2700 2500)(-1450 2500);
FORCEPROP 0 LAST CDS_PHYS_NET_NAME FM_SLPS3_GF_N
J 0
(-2675 2542);
PAINT MONO (-2675 2542);
DISPLAY INVISIBLE (-2675 2542);
FORCEPROP 0 LAST SIG_NAME RST_MB_STBY_N
J 0
(-2225 2510);
DISPLAY 0.702128 (-2225 2510);
PAINT WHITE (-2225 2510);
WIRE 16 -1 (-2700 2275)(-1450 2275);
FORCEPROP 0 LAST CDS_PHYS_NET_NAME FM_SLPS3_GF_N
J 0
(-2675 2317);
PAINT MONO (-2675 2317);
DISPLAY INVISIBLE (-2675 2317);
FORCEPROP 0 LAST SIG_NAME RST_RSMRST_PCH_N
J 0
(-2225 2285);
DISPLAY 0.702128 (-2225 2285);
PAINT WHITE (-2225 2285);
WIRE 16 -1 (-2700 2075)(-1275 2075);
FORCEPROP 0 LAST CDS_PHYS_NET_NAME RST_PLTRST_PLD_N
J 0
(-2675 2117);
PAINT MONO (-2675 2117);
DISPLAY INVISIBLE (-2675 2117);
FORCEPROP 0 LAST SIG_NAME RST_RSMRST_NM_HDR_N
J 0
(-2225 2085);
DISPLAY 0.702128 (-2225 2085);
PAINT WHITE (-2225 2085);
WIRE 16 -1 (-4150 2500)(-2900 2500);
FORCEPROP 0 LAST CDS_PHYS_NET_NAME FM_PCH_SLP_S3_N
J 0
(-4125 2542);
PAINT MONO (-4125 2542);
DISPLAY INVISIBLE (-4125 2542);
FORCEPROP 0 LAST SIG_NAME RST_MB_STBY_R_N
J 0
(-3950 2510);
DISPLAY 0.702128 (-3950 2510);
PAINT WHITE (-3950 2510);
WIRE 16 -1 (-3300 2750)(-3675 2750);
WIRE 16 -1 (-4150 2925)(-3300 2925);
FORCEPROP 0 LAST CDS_PHYS_NET_NAME FM_PCH_SLP_S3_N
J 0
(-4125 2967);
PAINT MONO (-4125 2967);
DISPLAY INVISIBLE (-4125 2967);
FORCEPROP 0 LAST SIG_NAME RST_PLTRST_N
J 0
(-3950 2935);
DISPLAY 0.702128 (-3950 2935);
PAINT WHITE (-3950 2935);
WIRE 16 -1 (-3300 2925)(-3300 2750);
WIRE 16 -1 (-3300 2925)(-2900 2925);
WIRE 16 -1 (475 2875)(1800 2875);
FORCEPROP 0 LAST CDS_PHYS_NET_NAME RST_PLTRST_N
J 0
(500 2917);
PAINT MONO (500 2917);
DISPLAY INVISIBLE (500 2917);
FORCEPROP 0 LAST SIG_NAME RST_PCIE_CPU0_DEV_PERST_N
J 0
(575 2885);
DISPLAY 0.702128 (575 2885);
PAINT WHITE (575 2885);
WIRE 16 -1 (2000 2875)(3425 2875);
FORCEPROP 0 LAST CDS_PHYS_NET_NAME RST_OCP_V3_1_N
J 0
(2025 2917);
PAINT MONO (2025 2917);
DISPLAY INVISIBLE (2025 2917);
FORCEPROP 0 LAST SIG_NAME RST_OCP_V3_1_N
J 0
(2475 2885);
DISPLAY 0.702128 (2475 2885);
PAINT WHITE (2475 2885);
WIRE 16 -1 (2025 3375)(3450 3375);
FORCEPROP 0 LAST CDS_PHYS_NET_NAME RST_PLTRST_PLD_N
J 0
(2050 3417);
PAINT MONO (2050 3417);
DISPLAY INVISIBLE (2050 3417);
FORCEPROP 0 LAST SIG_NAME RST_PLTRST_B_MUX_N
J 0
(2500 3385);
DISPLAY 0.702128 (2500 3385);
PAINT WHITE (2500 3385);
WIRE 16 -1 (2025 3575)(3450 3575);
FORCEPROP 0 LAST CDS_PHYS_NET_NAME RST_PLTRST_PLD_N
J 0
(2050 3617);
PAINT MONO (2050 3617);
DISPLAY INVISIBLE (2050 3617);
FORCEPROP 0 LAST SIG_NAME RST_PLTRST_B_N
J 0
(2500 3585);
DISPLAY 0.702128 (2500 3585);
PAINT WHITE (2500 3585);
WIRE 16 -1 (-4150 2750)(-3875 2750);
WIRE 16 -1 (-4150 2275)(-3200 2275);
FORCEPROP 0 LAST CDS_PHYS_NET_NAME FM_PCH_SLP_S3_N
J 0
(-4125 2317);
PAINT MONO (-4125 2317);
DISPLAY INVISIBLE (-4125 2317);
FORCEPROP 0 LAST SIG_NAME RST_RSMRST_PLD_R_N
J 0
(-3950 2285);
DISPLAY 0.702128 (-3950 2285);
PAINT WHITE (-3950 2285);
WIRE 16 -1 (-3200 2275)(-2900 2275);
WIRE 16 -1 (-3200 2275)(-3200 2075);
WIRE 16 -1 (-3200 2075)(-2900 2075);
WIRE 16 -1 (-4150 3350)(-2900 3350);
FORCEPROP 0 LAST CDS_PHYS_NET_NAME FM_PCH_SLP_S3_N
J 0
(-4125 3392);
PAINT MONO (-4125 3392);
DISPLAY INVISIBLE (-4125 3392);
FORCEPROP 0 LAST SIG_NAME FM_PCH_SLP_S3_N
J 0
(-3950 3360);
DISPLAY 0.702128 (-3950 3360);
PAINT WHITE (-3950 3360);
WIRE 16 -1 (475 -550)(1775 -550);
FORCEPROP 0 LAST CDS_PHYS_NET_NAME FM_PCH_SLP_S3_N
J 0
(500 -508);
PAINT MONO (500 -508);
DISPLAY INVISIBLE (500 -508);
FORCEPROP 0 LAST SIG_NAME FM_ADR_MODE1
J 0
(575 -540);
DISPLAY 0.702128 (575 -540);
PAINT WHITE (575 -540);
WIRE 16 -1 (1975 -550)(3425 -550);
FORCEPROP 0 LAST CDS_PHYS_NET_NAME FM_SLPS3_GF_N
J 0
(2000 -508);
PAINT MONO (2000 -508);
DISPLAY INVISIBLE (2000 -508);
FORCEPROP 0 LAST SIG_NAME FM_ADR_MODE1_R
J 0
(2475 -540);
DISPLAY 0.702128 (2475 -540);
PAINT WHITE (2475 -540);
WIRE 16 -1 (-4150 3150)(-2900 3150);
FORCEPROP 0 LAST CDS_PHYS_NET_NAME FM_PCH_SLP_S3_N
J 0
(-4125 3192);
PAINT MONO (-4125 3192);
DISPLAY INVISIBLE (-4125 3192);
FORCEPROP 0 LAST SIG_NAME FM_PCH_SLP_S4_N
J 0
(-3950 3160);
DISPLAY 0.702128 (-3950 3160);
PAINT WHITE (-3950 3160);
WIRE 16 -1 (-2700 3150)(-1450 3150);
FORCEPROP 0 LAST CDS_PHYS_NET_NAME FM_SLPS3_GF_N
J 0
(-2675 3192);
PAINT MONO (-2675 3192);
DISPLAY INVISIBLE (-2675 3192);
FORCEPROP 0 LAST SIG_NAME FM_SLPS4_PLD_N
J 0
(-2225 3160);
DISPLAY 0.702128 (-2225 3160);
PAINT WHITE (-2225 3160);
WIRE 16 -1 (-2700 2925)(-1450 2925);
FORCEPROP 0 LAST CDS_PHYS_NET_NAME FM_SLPS3_GF_N
J 0
(-2675 2967);
PAINT MONO (-2675 2967);
DISPLAY INVISIBLE (-2675 2967);
FORCEPROP 0 LAST SIG_NAME RST_PLTRST_PLD_N
J 0
(-2225 2935);
DISPLAY 0.702128 (-2225 2935);
PAINT WHITE (-2225 2935);
WIRE 16 -1 (-4150 3550)(-2900 3550);
FORCEPROP 0 LAST CDS_PHYS_NET_NAME FM_PCH_SLP_S3_N
J 0
(-4125 3592);
PAINT MONO (-4125 3592);
DISPLAY INVISIBLE (-4125 3592);
FORCEPROP 0 LAST SIG_NAME FM_PLD_CLK_25M_R_EN
J 0
(-3950 3560);
DISPLAY 0.702128 (-3950 3560);
PAINT WHITE (-3950 3560);
WIRE 16 -1 (-2700 3550)(-1450 3550);
FORCEPROP 0 LAST CDS_PHYS_NET_NAME FM_SLPS3_GF_N
J 0
(-2675 3592);
PAINT MONO (-2675 3592);
DISPLAY INVISIBLE (-2675 3592);
FORCEPROP 0 LAST SIG_NAME FM_PLD_CLK_25M_EN
J 0
(-2225 3560);
DISPLAY 0.702128 (-2225 3560);
PAINT WHITE (-2225 3560);
WIRE 16 -1 (-2700 3775)(-1450 3775);
FORCEPROP 0 LAST SIG_NAME FM_BMC_PWRBTN_N
J 0
(-2225 3785);
DISPLAY 0.702128 (-2225 3785);
PAINT WHITE (-2225 3785);
DOT 1 (-3200 2275);
DOT 1 (1525 3575);
DOT 1 (-2750 825);
DOT 1 (-3300 2925);
FORCENOTE
20211126 CHANGE TO P3V3
(-3200 1400) 0;
DISPLAY LEFT (-3200 1400);
DISPLAY 1.021277 (-3200 1400);
PAINT PINK (-3200 1400);
FORCENOTE
20211130 CHANGE TP 0 OHM
(1275 4000) 0;
DISPLAY LEFT (1275 4000);
DISPLAY 1.276596 (1275 4000);
PAINT PINK (1275 4000);
FORCENOTE
TO BMC
(3375 3650) 0;
DISPLAY LEFT (3375 3650);
DISPLAY 1.021277 (3375 3650);
PAINT YELLOW (3375 3650);
FORCENOTE
20210902 MODIFY FOR GT
(-4900 4225) 0;
DISPLAY LEFT (-4900 4225);
DISPLAY 2.510638 (-4900 4225);
PAINT PINK (-4900 4225);
QUIT
